FILE_TYPE = MACRO_DRAWING;
SET COLOR_WIRE YELLOW;
SET COLOR_PROP MONO;
SET COLOR_DOT WHITE;
SET COLOR_ARC YELLOW;
SET COLOR_BODY GREEN;
SET COLOR_NOTE MONO;
SET PROP_DISPLAY VALUE;
SET PAGE_NUMBER P65;
FORCEADD TAP..1
R 2
(-5575 2125);
FORCEPROP 3 LASTPIN (-5525 2125) SIG_NAME TP_P3E_CPU1_PE2_RSR_RXN<4>
J 0
(-5515 2135);
DISPLAY 0.659574 (-5515 2135);
PAINT MONO (-5515 2135);
DISPLAY INVISIBLE (-5515 2135);
FORCEPROP 1 LASTPIN (-5525 2125) BN 4
J 2
(-5513 2133);
DISPLAY 0.617021 (-5513 2133);
PAINT GREEN (-5513 2133);
FORCEPROP 2 LAST CDS_LIB mstr_standard
J 0
(-5575 2125);
PAINT MONO (-5575 2125);
DISPLAY INVISIBLE (-5575 2125);
FORCEPROP 1 LAST BODY_TYPE PLUMBING
J 2
(-5575 2175);
DISPLAY 1.446809 (-5575 2175);
PAINT GREEN (-5575 2175);
DISPLAY INVISIBLE (-5575 2175);
FORCEPROP 1 LAST HDL_TAP TRUE
J 2
(-5900 2000);
DISPLAY 1.446809 (-5900 2000);
PAINT GREEN (-5900 2000);
DISPLAY INVISIBLE (-5900 2000);
FORCEPROP 1 LAST PATH I11
J 2
(-5573 2125);
DISPLAY 0.872340 (-5573 2125);
PAINT GREEN (-5573 2125);
DISPLAY INVISIBLE (-5573 2125);
FORCEADD TAP..1
R 2
(-5575 2225);
FORCEPROP 3 LASTPIN (-5525 2225) SIG_NAME TP_P3E_CPU1_PE2_RSR_RXN<6>
J 0
(-5515 2235);
DISPLAY 0.659574 (-5515 2235);
PAINT MONO (-5515 2235);
DISPLAY INVISIBLE (-5515 2235);
FORCEPROP 1 LASTPIN (-5525 2225) BN 6
J 2
(-5513 2233);
DISPLAY 0.617021 (-5513 2233);
PAINT GREEN (-5513 2233);
FORCEPROP 2 LAST CDS_LIB mstr_standard
J 0
(-5575 2225);
PAINT MONO (-5575 2225);
DISPLAY INVISIBLE (-5575 2225);
FORCEPROP 1 LAST BODY_TYPE PLUMBING
J 2
(-5575 2275);
DISPLAY 1.446809 (-5575 2275);
PAINT GREEN (-5575 2275);
DISPLAY INVISIBLE (-5575 2275);
FORCEPROP 1 LAST HDL_TAP TRUE
J 2
(-5900 2100);
DISPLAY 1.446809 (-5900 2100);
PAINT GREEN (-5900 2100);
DISPLAY INVISIBLE (-5900 2100);
FORCEPROP 1 LAST PATH I12
J 2
(-5573 2225);
DISPLAY 0.872340 (-5573 2225);
PAINT GREEN (-5573 2225);
DISPLAY INVISIBLE (-5573 2225);
FORCEADD TAP..1
R 2
(-5575 2175);
FORCEPROP 3 LASTPIN (-5525 2175) SIG_NAME TP_P3E_CPU1_PE2_RSR_RXN<5>
J 0
(-5515 2185);
DISPLAY 0.659574 (-5515 2185);
PAINT MONO (-5515 2185);
DISPLAY INVISIBLE (-5515 2185);
FORCEPROP 1 LASTPIN (-5525 2175) BN 5
J 2
(-5513 2183);
DISPLAY 0.617021 (-5513 2183);
PAINT GREEN (-5513 2183);
FORCEPROP 2 LAST CDS_LIB mstr_standard
J 0
(-5575 2175);
PAINT MONO (-5575 2175);
DISPLAY INVISIBLE (-5575 2175);
FORCEPROP 1 LAST BODY_TYPE PLUMBING
J 2
(-5575 2225);
DISPLAY 1.446809 (-5575 2225);
PAINT GREEN (-5575 2225);
DISPLAY INVISIBLE (-5575 2225);
FORCEPROP 1 LAST HDL_TAP TRUE
J 2
(-5900 2050);
DISPLAY 1.446809 (-5900 2050);
PAINT GREEN (-5900 2050);
DISPLAY INVISIBLE (-5900 2050);
FORCEPROP 1 LAST PATH I13
J 2
(-5573 2175);
DISPLAY 0.872340 (-5573 2175);
PAINT GREEN (-5573 2175);
DISPLAY INVISIBLE (-5573 2175);
FORCEADD TAP..1
R 2
(-5575 2275);
FORCEPROP 3 LASTPIN (-5525 2275) SIG_NAME TP_P3E_CPU1_PE2_RSR_RXN<7>
J 0
(-5515 2285);
DISPLAY 0.659574 (-5515 2285);
PAINT MONO (-5515 2285);
DISPLAY INVISIBLE (-5515 2285);
FORCEPROP 1 LASTPIN (-5525 2275) BN 7
J 2
(-5513 2283);
DISPLAY 0.617021 (-5513 2283);
PAINT GREEN (-5513 2283);
FORCEPROP 2 LAST CDS_LIB mstr_standard
J 0
(-5575 2275);
PAINT MONO (-5575 2275);
DISPLAY INVISIBLE (-5575 2275);
FORCEPROP 1 LAST BODY_TYPE PLUMBING
J 2
(-5575 2325);
DISPLAY 1.446809 (-5575 2325);
PAINT GREEN (-5575 2325);
DISPLAY INVISIBLE (-5575 2325);
FORCEPROP 1 LAST HDL_TAP TRUE
J 2
(-5900 2150);
DISPLAY 1.446809 (-5900 2150);
PAINT GREEN (-5900 2150);
DISPLAY INVISIBLE (-5900 2150);
FORCEPROP 1 LAST PATH I14
J 2
(-5573 2275);
DISPLAY 0.872340 (-5573 2275);
PAINT GREEN (-5573 2275);
DISPLAY INVISIBLE (-5573 2275);
FORCEADD TAP..1
R 2
(-5425 2025);
FORCEPROP 3 LASTPIN (-5375 2025) SIG_NAME TP_P3E_CPU1_PE2_RSR_RXP<3>
J 0
(-5365 2035);
DISPLAY 0.659574 (-5365 2035);
PAINT MONO (-5365 2035);
DISPLAY INVISIBLE (-5365 2035);
FORCEPROP 1 LASTPIN (-5375 2025) BN 3
J 2
(-5363 2033);
DISPLAY 0.617021 (-5363 2033);
PAINT GREEN (-5363 2033);
FORCEPROP 2 LAST CDS_LIB mstr_standard
J 0
(-5425 2025);
PAINT MONO (-5425 2025);
DISPLAY INVISIBLE (-5425 2025);
FORCEPROP 1 LAST BODY_TYPE PLUMBING
J 2
(-5425 2075);
DISPLAY 1.446809 (-5425 2075);
PAINT GREEN (-5425 2075);
DISPLAY INVISIBLE (-5425 2075);
FORCEPROP 1 LAST HDL_TAP TRUE
J 2
(-5750 1900);
DISPLAY 1.446809 (-5750 1900);
PAINT GREEN (-5750 1900);
DISPLAY INVISIBLE (-5750 1900);
FORCEPROP 1 LAST PATH I15
J 2
(-5423 2025);
DISPLAY 0.872340 (-5423 2025);
PAINT GREEN (-5423 2025);
DISPLAY INVISIBLE (-5423 2025);
FORCEADD TAP..1
R 2
(-5425 2375);
FORCEPROP 3 LASTPIN (-5375 2375) SIG_NAME TP_P3E_CPU1_PE2_RSR_RXP<4>
J 0
(-5365 2385);
DISPLAY 0.659574 (-5365 2385);
PAINT MONO (-5365 2385);
DISPLAY INVISIBLE (-5365 2385);
FORCEPROP 1 LASTPIN (-5375 2375) BN 4
J 2
(-5363 2383);
DISPLAY 0.617021 (-5363 2383);
PAINT GREEN (-5363 2383);
FORCEPROP 2 LAST CDS_LIB mstr_standard
J 0
(-5425 2375);
PAINT MONO (-5425 2375);
DISPLAY INVISIBLE (-5425 2375);
FORCEPROP 1 LAST BODY_TYPE PLUMBING
J 2
(-5425 2425);
DISPLAY 1.446809 (-5425 2425);
PAINT GREEN (-5425 2425);
DISPLAY INVISIBLE (-5425 2425);
FORCEPROP 1 LAST HDL_TAP TRUE
J 2
(-5750 2250);
DISPLAY 1.446809 (-5750 2250);
PAINT GREEN (-5750 2250);
DISPLAY INVISIBLE (-5750 2250);
FORCEPROP 1 LAST PATH I16
J 2
(-5423 2375);
DISPLAY 0.872340 (-5423 2375);
PAINT GREEN (-5423 2375);
DISPLAY INVISIBLE (-5423 2375);
FORCEADD TAP..1
R 2
(-5425 2425);
FORCEPROP 3 LASTPIN (-5375 2425) SIG_NAME TP_P3E_CPU1_PE2_RSR_RXP<5>
J 0
(-5365 2435);
DISPLAY 0.659574 (-5365 2435);
PAINT MONO (-5365 2435);
DISPLAY INVISIBLE (-5365 2435);
FORCEPROP 1 LASTPIN (-5375 2425) BN 5
J 2
(-5363 2433);
DISPLAY 0.617021 (-5363 2433);
PAINT GREEN (-5363 2433);
FORCEPROP 2 LAST CDS_LIB mstr_standard
J 0
(-5425 2425);
PAINT MONO (-5425 2425);
DISPLAY INVISIBLE (-5425 2425);
FORCEPROP 1 LAST BODY_TYPE PLUMBING
J 2
(-5425 2475);
DISPLAY 1.446809 (-5425 2475);
PAINT GREEN (-5425 2475);
DISPLAY INVISIBLE (-5425 2475);
FORCEPROP 1 LAST HDL_TAP TRUE
J 2
(-5750 2300);
DISPLAY 1.446809 (-5750 2300);
PAINT GREEN (-5750 2300);
DISPLAY INVISIBLE (-5750 2300);
FORCEPROP 1 LAST PATH I17
J 2
(-5423 2425);
DISPLAY 0.872340 (-5423 2425);
PAINT GREEN (-5423 2425);
DISPLAY INVISIBLE (-5423 2425);
FORCEADD TAP..1
R 2
(-5425 2475);
FORCEPROP 3 LASTPIN (-5375 2475) SIG_NAME TP_P3E_CPU1_PE2_RSR_RXP<6>
J 0
(-5365 2485);
DISPLAY 0.659574 (-5365 2485);
PAINT MONO (-5365 2485);
DISPLAY INVISIBLE (-5365 2485);
FORCEPROP 1 LASTPIN (-5375 2475) BN 6
J 2
(-5363 2483);
DISPLAY 0.617021 (-5363 2483);
PAINT GREEN (-5363 2483);
FORCEPROP 2 LAST CDS_LIB mstr_standard
J 0
(-5425 2475);
PAINT MONO (-5425 2475);
DISPLAY INVISIBLE (-5425 2475);
FORCEPROP 1 LAST BODY_TYPE PLUMBING
J 2
(-5425 2525);
DISPLAY 1.446809 (-5425 2525);
PAINT GREEN (-5425 2525);
DISPLAY INVISIBLE (-5425 2525);
FORCEPROP 1 LAST HDL_TAP TRUE
J 2
(-5750 2350);
DISPLAY 1.446809 (-5750 2350);
PAINT GREEN (-5750 2350);
DISPLAY INVISIBLE (-5750 2350);
FORCEPROP 1 LAST PATH I18
J 2
(-5423 2475);
DISPLAY 0.872340 (-5423 2475);
PAINT GREEN (-5423 2475);
DISPLAY INVISIBLE (-5423 2475);
FORCEADD TAP..1
R 2
(-5575 2625);
FORCEPROP 3 LASTPIN (-5525 2625) SIG_NAME TP_P3E_CPU1_PE2_RSR_RXN<8>
J 0
(-5515 2635);
DISPLAY 0.659574 (-5515 2635);
PAINT MONO (-5515 2635);
DISPLAY INVISIBLE (-5515 2635);
FORCEPROP 1 LASTPIN (-5525 2625) BN 8
J 2
(-5513 2633);
DISPLAY 0.617021 (-5513 2633);
PAINT GREEN (-5513 2633);
FORCEPROP 2 LAST CDS_LIB mstr_standard
J 0
(-5575 2625);
PAINT MONO (-5575 2625);
DISPLAY INVISIBLE (-5575 2625);
FORCEPROP 1 LAST BODY_TYPE PLUMBING
J 2
(-5575 2675);
DISPLAY 1.446809 (-5575 2675);
PAINT GREEN (-5575 2675);
DISPLAY INVISIBLE (-5575 2675);
FORCEPROP 1 LAST HDL_TAP TRUE
J 2
(-5900 2500);
DISPLAY 1.446809 (-5900 2500);
PAINT GREEN (-5900 2500);
DISPLAY INVISIBLE (-5900 2500);
FORCEPROP 1 LAST PATH I19
J 2
(-5573 2625);
DISPLAY 0.872340 (-5573 2625);
PAINT GREEN (-5573 2625);
DISPLAY INVISIBLE (-5573 2625);
FORCEADD TAP..1
R 2
(-5575 2725);
FORCEPROP 3 LASTPIN (-5525 2725) SIG_NAME TP_P3E_CPU1_PE2_RSR_RXN<10>
J 0
(-5515 2735);
DISPLAY 0.659574 (-5515 2735);
PAINT MONO (-5515 2735);
DISPLAY INVISIBLE (-5515 2735);
FORCEPROP 1 LASTPIN (-5525 2725) BN 10
J 2
(-5513 2733);
DISPLAY 0.617021 (-5513 2733);
PAINT GREEN (-5513 2733);
FORCEPROP 2 LAST CDS_LIB mstr_standard
J 0
(-5575 2725);
PAINT MONO (-5575 2725);
DISPLAY INVISIBLE (-5575 2725);
FORCEPROP 1 LAST BODY_TYPE PLUMBING
J 2
(-5575 2775);
DISPLAY 1.446809 (-5575 2775);
PAINT GREEN (-5575 2775);
DISPLAY INVISIBLE (-5575 2775);
FORCEPROP 1 LAST HDL_TAP TRUE
J 2
(-5900 2600);
DISPLAY 1.446809 (-5900 2600);
PAINT GREEN (-5900 2600);
DISPLAY INVISIBLE (-5900 2600);
FORCEPROP 1 LAST PATH I20
J 2
(-5573 2725);
DISPLAY 0.872340 (-5573 2725);
PAINT GREEN (-5573 2725);
DISPLAY INVISIBLE (-5573 2725);
FORCEADD TAP..1
R 2
(-5575 2675);
FORCEPROP 3 LASTPIN (-5525 2675) SIG_NAME TP_P3E_CPU1_PE2_RSR_RXN<9>
J 0
(-5515 2685);
DISPLAY 0.659574 (-5515 2685);
PAINT MONO (-5515 2685);
DISPLAY INVISIBLE (-5515 2685);
FORCEPROP 1 LASTPIN (-5525 2675) BN 9
J 2
(-5513 2683);
DISPLAY 0.617021 (-5513 2683);
PAINT GREEN (-5513 2683);
FORCEPROP 2 LAST CDS_LIB mstr_standard
J 0
(-5575 2675);
PAINT MONO (-5575 2675);
DISPLAY INVISIBLE (-5575 2675);
FORCEPROP 1 LAST BODY_TYPE PLUMBING
J 2
(-5575 2725);
DISPLAY 1.446809 (-5575 2725);
PAINT GREEN (-5575 2725);
DISPLAY INVISIBLE (-5575 2725);
FORCEPROP 1 LAST HDL_TAP TRUE
J 2
(-5900 2550);
DISPLAY 1.446809 (-5900 2550);
PAINT GREEN (-5900 2550);
DISPLAY INVISIBLE (-5900 2550);
FORCEPROP 1 LAST PATH I21
J 2
(-5573 2675);
DISPLAY 0.872340 (-5573 2675);
PAINT GREEN (-5573 2675);
DISPLAY INVISIBLE (-5573 2675);
FORCEADD TAP..1
R 2
(-5575 2775);
FORCEPROP 3 LASTPIN (-5525 2775) SIG_NAME TP_P3E_CPU1_PE2_RSR_RXN<11>
J 0
(-5515 2785);
DISPLAY 0.659574 (-5515 2785);
PAINT MONO (-5515 2785);
DISPLAY INVISIBLE (-5515 2785);
FORCEPROP 1 LASTPIN (-5525 2775) BN 11
J 2
(-5513 2783);
DISPLAY 0.617021 (-5513 2783);
PAINT GREEN (-5513 2783);
FORCEPROP 2 LAST CDS_LIB mstr_standard
J 0
(-5575 2775);
PAINT MONO (-5575 2775);
DISPLAY INVISIBLE (-5575 2775);
FORCEPROP 1 LAST BODY_TYPE PLUMBING
J 2
(-5575 2825);
DISPLAY 1.446809 (-5575 2825);
PAINT GREEN (-5575 2825);
DISPLAY INVISIBLE (-5575 2825);
FORCEPROP 1 LAST HDL_TAP TRUE
J 2
(-5900 2650);
DISPLAY 1.446809 (-5900 2650);
PAINT GREEN (-5900 2650);
DISPLAY INVISIBLE (-5900 2650);
FORCEPROP 1 LAST PATH I22
J 2
(-5573 2775);
DISPLAY 0.872340 (-5573 2775);
PAINT GREEN (-5573 2775);
DISPLAY INVISIBLE (-5573 2775);
FORCEADD TAP..1
R 2
(-5425 2525);
FORCEPROP 3 LASTPIN (-5375 2525) SIG_NAME TP_P3E_CPU1_PE2_RSR_RXP<7>
J 0
(-5365 2535);
DISPLAY 0.659574 (-5365 2535);
PAINT MONO (-5365 2535);
DISPLAY INVISIBLE (-5365 2535);
FORCEPROP 1 LASTPIN (-5375 2525) BN 7
J 2
(-5363 2533);
DISPLAY 0.617021 (-5363 2533);
PAINT GREEN (-5363 2533);
FORCEPROP 2 LAST CDS_LIB mstr_standard
J 0
(-5425 2525);
PAINT MONO (-5425 2525);
DISPLAY INVISIBLE (-5425 2525);
FORCEPROP 1 LAST BODY_TYPE PLUMBING
J 2
(-5425 2575);
DISPLAY 1.446809 (-5425 2575);
PAINT GREEN (-5425 2575);
DISPLAY INVISIBLE (-5425 2575);
FORCEPROP 1 LAST HDL_TAP TRUE
J 2
(-5750 2400);
DISPLAY 1.446809 (-5750 2400);
PAINT GREEN (-5750 2400);
DISPLAY INVISIBLE (-5750 2400);
FORCEPROP 1 LAST PATH I23
J 2
(-5423 2525);
DISPLAY 0.872340 (-5423 2525);
PAINT GREEN (-5423 2525);
DISPLAY INVISIBLE (-5423 2525);
FORCEADD TAP..1
R 2
(-5425 2875);
FORCEPROP 3 LASTPIN (-5375 2875) SIG_NAME TP_P3E_CPU1_PE2_RSR_RXP<8>
J 0
(-5365 2885);
DISPLAY 0.659574 (-5365 2885);
PAINT MONO (-5365 2885);
DISPLAY INVISIBLE (-5365 2885);
FORCEPROP 1 LASTPIN (-5375 2875) BN 8
J 2
(-5363 2883);
DISPLAY 0.617021 (-5363 2883);
PAINT GREEN (-5363 2883);
FORCEPROP 2 LAST CDS_LIB mstr_standard
J 0
(-5425 2875);
PAINT MONO (-5425 2875);
DISPLAY INVISIBLE (-5425 2875);
FORCEPROP 1 LAST BODY_TYPE PLUMBING
J 2
(-5425 2925);
DISPLAY 1.446809 (-5425 2925);
PAINT GREEN (-5425 2925);
DISPLAY INVISIBLE (-5425 2925);
FORCEPROP 1 LAST HDL_TAP TRUE
J 2
(-5750 2750);
DISPLAY 1.446809 (-5750 2750);
PAINT GREEN (-5750 2750);
DISPLAY INVISIBLE (-5750 2750);
FORCEPROP 1 LAST PATH I24
J 2
(-5423 2875);
DISPLAY 0.872340 (-5423 2875);
PAINT GREEN (-5423 2875);
DISPLAY INVISIBLE (-5423 2875);
FORCEADD TAP..1
R 2
(-5425 2925);
FORCEPROP 3 LASTPIN (-5375 2925) SIG_NAME TP_P3E_CPU1_PE2_RSR_RXP<9>
J 0
(-5365 2935);
DISPLAY 0.659574 (-5365 2935);
PAINT MONO (-5365 2935);
DISPLAY INVISIBLE (-5365 2935);
FORCEPROP 1 LASTPIN (-5375 2925) BN 9
J 2
(-5363 2933);
DISPLAY 0.617021 (-5363 2933);
PAINT GREEN (-5363 2933);
FORCEPROP 2 LAST CDS_LIB mstr_standard
J 0
(-5425 2925);
PAINT MONO (-5425 2925);
DISPLAY INVISIBLE (-5425 2925);
FORCEPROP 1 LAST BODY_TYPE PLUMBING
J 2
(-5425 2975);
DISPLAY 1.446809 (-5425 2975);
PAINT GREEN (-5425 2975);
DISPLAY INVISIBLE (-5425 2975);
FORCEPROP 1 LAST HDL_TAP TRUE
J 2
(-5750 2800);
DISPLAY 1.446809 (-5750 2800);
PAINT GREEN (-5750 2800);
DISPLAY INVISIBLE (-5750 2800);
FORCEPROP 1 LAST PATH I25
J 2
(-5423 2925);
DISPLAY 0.872340 (-5423 2925);
PAINT GREEN (-5423 2925);
DISPLAY INVISIBLE (-5423 2925);
FORCEADD TAP..1
R 2
(-5425 2975);
FORCEPROP 3 LASTPIN (-5375 2975) SIG_NAME TP_P3E_CPU1_PE2_RSR_RXP<10>
J 0
(-5365 2985);
DISPLAY 0.659574 (-5365 2985);
PAINT MONO (-5365 2985);
DISPLAY INVISIBLE (-5365 2985);
FORCEPROP 1 LASTPIN (-5375 2975) BN 10
J 2
(-5363 2983);
DISPLAY 0.617021 (-5363 2983);
PAINT GREEN (-5363 2983);
FORCEPROP 2 LAST CDS_LIB mstr_standard
J 0
(-5425 2975);
PAINT MONO (-5425 2975);
DISPLAY INVISIBLE (-5425 2975);
FORCEPROP 1 LAST BODY_TYPE PLUMBING
J 2
(-5425 3025);
DISPLAY 1.446809 (-5425 3025);
PAINT GREEN (-5425 3025);
DISPLAY INVISIBLE (-5425 3025);
FORCEPROP 1 LAST HDL_TAP TRUE
J 2
(-5750 2850);
DISPLAY 1.446809 (-5750 2850);
PAINT GREEN (-5750 2850);
DISPLAY INVISIBLE (-5750 2850);
FORCEPROP 1 LAST PATH I26
J 2
(-5423 2975);
DISPLAY 0.872340 (-5423 2975);
PAINT GREEN (-5423 2975);
DISPLAY INVISIBLE (-5423 2975);
FORCEADD TAP..1
R 2
(-5575 3125);
FORCEPROP 3 LASTPIN (-5525 3125) SIG_NAME TP_P3E_CPU1_PE2_RSR_RXN<12>
J 0
(-5515 3135);
DISPLAY 0.659574 (-5515 3135);
PAINT MONO (-5515 3135);
DISPLAY INVISIBLE (-5515 3135);
FORCEPROP 1 LASTPIN (-5525 3125) BN 12
J 2
(-5513 3133);
DISPLAY 0.617021 (-5513 3133);
PAINT GREEN (-5513 3133);
FORCEPROP 2 LAST CDS_LIB mstr_standard
J 0
(-5575 3125);
PAINT MONO (-5575 3125);
DISPLAY INVISIBLE (-5575 3125);
FORCEPROP 1 LAST BODY_TYPE PLUMBING
J 2
(-5575 3175);
DISPLAY 1.446809 (-5575 3175);
PAINT GREEN (-5575 3175);
DISPLAY INVISIBLE (-5575 3175);
FORCEPROP 1 LAST HDL_TAP TRUE
J 2
(-5900 3000);
DISPLAY 1.446809 (-5900 3000);
PAINT GREEN (-5900 3000);
DISPLAY INVISIBLE (-5900 3000);
FORCEPROP 1 LAST PATH I27
J 2
(-5573 3125);
DISPLAY 0.872340 (-5573 3125);
PAINT GREEN (-5573 3125);
DISPLAY INVISIBLE (-5573 3125);
FORCEADD TAP..1
R 2
(-5575 3225);
FORCEPROP 3 LASTPIN (-5525 3225) SIG_NAME TP_P3E_CPU1_PE2_RSR_RXN<14>
J 0
(-5515 3235);
DISPLAY 0.659574 (-5515 3235);
PAINT MONO (-5515 3235);
DISPLAY INVISIBLE (-5515 3235);
FORCEPROP 1 LASTPIN (-5525 3225) BN 14
J 2
(-5513 3233);
DISPLAY 0.617021 (-5513 3233);
PAINT GREEN (-5513 3233);
FORCEPROP 2 LAST CDS_LIB mstr_standard
J 0
(-5575 3225);
PAINT MONO (-5575 3225);
DISPLAY INVISIBLE (-5575 3225);
FORCEPROP 1 LAST BODY_TYPE PLUMBING
J 2
(-5575 3275);
DISPLAY 1.446809 (-5575 3275);
PAINT GREEN (-5575 3275);
DISPLAY INVISIBLE (-5575 3275);
FORCEPROP 1 LAST HDL_TAP TRUE
J 2
(-5900 3100);
DISPLAY 1.446809 (-5900 3100);
PAINT GREEN (-5900 3100);
DISPLAY INVISIBLE (-5900 3100);
FORCEPROP 1 LAST PATH I28
J 2
(-5573 3225);
DISPLAY 0.872340 (-5573 3225);
PAINT GREEN (-5573 3225);
DISPLAY INVISIBLE (-5573 3225);
FORCEADD TAP..1
R 2
(-5575 3175);
FORCEPROP 3 LASTPIN (-5525 3175) SIG_NAME TP_P3E_CPU1_PE2_RSR_RXN<13>
J 0
(-5515 3185);
DISPLAY 0.659574 (-5515 3185);
PAINT MONO (-5515 3185);
DISPLAY INVISIBLE (-5515 3185);
FORCEPROP 1 LASTPIN (-5525 3175) BN 13
J 2
(-5513 3183);
DISPLAY 0.617021 (-5513 3183);
PAINT GREEN (-5513 3183);
FORCEPROP 2 LAST CDS_LIB mstr_standard
J 0
(-5575 3175);
PAINT MONO (-5575 3175);
DISPLAY INVISIBLE (-5575 3175);
FORCEPROP 1 LAST BODY_TYPE PLUMBING
J 2
(-5575 3225);
DISPLAY 1.446809 (-5575 3225);
PAINT GREEN (-5575 3225);
DISPLAY INVISIBLE (-5575 3225);
FORCEPROP 1 LAST HDL_TAP TRUE
J 2
(-5900 3050);
DISPLAY 1.446809 (-5900 3050);
PAINT GREEN (-5900 3050);
DISPLAY INVISIBLE (-5900 3050);
FORCEPROP 1 LAST PATH I29
J 2
(-5573 3175);
DISPLAY 0.872340 (-5573 3175);
PAINT GREEN (-5573 3175);
DISPLAY INVISIBLE (-5573 3175);
FORCEADD TAP..1
R 2
(-5575 1725);
FORCEPROP 3 LASTPIN (-5525 1725) SIG_NAME TP_P3E_CPU1_PE2_RSR_RXN<2>
J 0
(-5515 1735);
DISPLAY 0.659574 (-5515 1735);
PAINT MONO (-5515 1735);
DISPLAY INVISIBLE (-5515 1735);
FORCEPROP 1 LASTPIN (-5525 1725) BN 2
J 2
(-5513 1733);
DISPLAY 0.617021 (-5513 1733);
PAINT GREEN (-5513 1733);
FORCEPROP 2 LAST CDS_LIB mstr_standard
J 0
(-5575 1725);
PAINT MONO (-5575 1725);
DISPLAY INVISIBLE (-5575 1725);
FORCEPROP 1 LAST BODY_TYPE PLUMBING
J 2
(-5575 1775);
DISPLAY 1.446809 (-5575 1775);
PAINT GREEN (-5575 1775);
DISPLAY INVISIBLE (-5575 1775);
FORCEPROP 1 LAST HDL_TAP TRUE
J 2
(-5900 1600);
DISPLAY 1.446809 (-5900 1600);
PAINT GREEN (-5900 1600);
DISPLAY INVISIBLE (-5900 1600);
FORCEPROP 1 LAST PATH I3
J 2
(-5573 1725);
DISPLAY 0.872340 (-5573 1725);
PAINT GREEN (-5573 1725);
DISPLAY INVISIBLE (-5573 1725);
FORCEADD TAP..1
R 2
(-5575 3275);
FORCEPROP 3 LASTPIN (-5525 3275) SIG_NAME TP_P3E_CPU1_PE2_RSR_RXN<15>
J 0
(-5515 3285);
DISPLAY 0.659574 (-5515 3285);
PAINT MONO (-5515 3285);
DISPLAY INVISIBLE (-5515 3285);
FORCEPROP 1 LASTPIN (-5525 3275) BN 15
J 2
(-5513 3283);
DISPLAY 0.617021 (-5513 3283);
PAINT GREEN (-5513 3283);
FORCEPROP 2 LAST CDS_LIB mstr_standard
J 0
(-5575 3275);
PAINT MONO (-5575 3275);
DISPLAY INVISIBLE (-5575 3275);
FORCEPROP 1 LAST BODY_TYPE PLUMBING
J 2
(-5575 3325);
DISPLAY 1.446809 (-5575 3325);
PAINT GREEN (-5575 3325);
DISPLAY INVISIBLE (-5575 3325);
FORCEPROP 1 LAST HDL_TAP TRUE
J 2
(-5900 3150);
DISPLAY 1.446809 (-5900 3150);
PAINT GREEN (-5900 3150);
DISPLAY INVISIBLE (-5900 3150);
FORCEPROP 1 LAST PATH I30
J 2
(-5573 3275);
DISPLAY 0.872340 (-5573 3275);
PAINT GREEN (-5573 3275);
DISPLAY INVISIBLE (-5573 3275);
FORCEADD TAP..1
R 2
(-5425 3025);
FORCEPROP 3 LASTPIN (-5375 3025) SIG_NAME TP_P3E_CPU1_PE2_RSR_RXP<11>
J 0
(-5365 3035);
DISPLAY 0.659574 (-5365 3035);
PAINT MONO (-5365 3035);
DISPLAY INVISIBLE (-5365 3035);
FORCEPROP 1 LASTPIN (-5375 3025) BN 11
J 2
(-5363 3033);
DISPLAY 0.617021 (-5363 3033);
PAINT GREEN (-5363 3033);
FORCEPROP 2 LAST CDS_LIB mstr_standard
J 0
(-5425 3025);
PAINT MONO (-5425 3025);
DISPLAY INVISIBLE (-5425 3025);
FORCEPROP 1 LAST BODY_TYPE PLUMBING
J 2
(-5425 3075);
DISPLAY 1.446809 (-5425 3075);
PAINT GREEN (-5425 3075);
DISPLAY INVISIBLE (-5425 3075);
FORCEPROP 1 LAST HDL_TAP TRUE
J 2
(-5750 2900);
DISPLAY 1.446809 (-5750 2900);
PAINT GREEN (-5750 2900);
DISPLAY INVISIBLE (-5750 2900);
FORCEPROP 1 LAST PATH I31
J 2
(-5423 3025);
DISPLAY 0.872340 (-5423 3025);
PAINT GREEN (-5423 3025);
DISPLAY INVISIBLE (-5423 3025);
FORCEADD TAP..1
R 2
(-5425 3375);
FORCEPROP 3 LASTPIN (-5375 3375) SIG_NAME TP_P3E_CPU1_PE2_RSR_RXP<12>
J 0
(-5365 3385);
DISPLAY 0.659574 (-5365 3385);
PAINT MONO (-5365 3385);
DISPLAY INVISIBLE (-5365 3385);
FORCEPROP 1 LASTPIN (-5375 3375) BN 12
J 2
(-5363 3383);
DISPLAY 0.617021 (-5363 3383);
PAINT GREEN (-5363 3383);
FORCEPROP 2 LAST CDS_LIB mstr_standard
J 0
(-5425 3375);
PAINT MONO (-5425 3375);
DISPLAY INVISIBLE (-5425 3375);
FORCEPROP 1 LAST BODY_TYPE PLUMBING
J 2
(-5425 3425);
DISPLAY 1.446809 (-5425 3425);
PAINT GREEN (-5425 3425);
DISPLAY INVISIBLE (-5425 3425);
FORCEPROP 1 LAST HDL_TAP TRUE
J 2
(-5750 3250);
DISPLAY 1.446809 (-5750 3250);
PAINT GREEN (-5750 3250);
DISPLAY INVISIBLE (-5750 3250);
FORCEPROP 1 LAST PATH I32
J 2
(-5423 3375);
DISPLAY 0.872340 (-5423 3375);
PAINT GREEN (-5423 3375);
DISPLAY INVISIBLE (-5423 3375);
FORCEADD TAP..1
R 2
(-5425 3475);
FORCEPROP 3 LASTPIN (-5375 3475) SIG_NAME TP_P3E_CPU1_PE2_RSR_RXP<14>
J 0
(-5365 3485);
DISPLAY 0.659574 (-5365 3485);
PAINT MONO (-5365 3485);
DISPLAY INVISIBLE (-5365 3485);
FORCEPROP 1 LASTPIN (-5375 3475) BN 14
J 2
(-5363 3483);
DISPLAY 0.617021 (-5363 3483);
PAINT GREEN (-5363 3483);
FORCEPROP 2 LAST CDS_LIB mstr_standard
J 0
(-5425 3475);
PAINT MONO (-5425 3475);
DISPLAY INVISIBLE (-5425 3475);
FORCEPROP 1 LAST BODY_TYPE PLUMBING
J 2
(-5425 3525);
DISPLAY 1.446809 (-5425 3525);
PAINT GREEN (-5425 3525);
DISPLAY INVISIBLE (-5425 3525);
FORCEPROP 1 LAST HDL_TAP TRUE
J 2
(-5750 3350);
DISPLAY 1.446809 (-5750 3350);
PAINT GREEN (-5750 3350);
DISPLAY INVISIBLE (-5750 3350);
FORCEPROP 1 LAST PATH I33
J 2
(-5423 3475);
DISPLAY 0.872340 (-5423 3475);
PAINT GREEN (-5423 3475);
DISPLAY INVISIBLE (-5423 3475);
FORCEADD TAP..1
R 2
(-5425 3425);
FORCEPROP 3 LASTPIN (-5375 3425) SIG_NAME TP_P3E_CPU1_PE2_RSR_RXP<13>
J 0
(-5365 3435);
DISPLAY 0.659574 (-5365 3435);
PAINT MONO (-5365 3435);
DISPLAY INVISIBLE (-5365 3435);
FORCEPROP 1 LASTPIN (-5375 3425) BN 13
J 2
(-5363 3433);
DISPLAY 0.617021 (-5363 3433);
PAINT GREEN (-5363 3433);
FORCEPROP 2 LAST CDS_LIB mstr_standard
J 0
(-5425 3425);
PAINT MONO (-5425 3425);
DISPLAY INVISIBLE (-5425 3425);
FORCEPROP 1 LAST BODY_TYPE PLUMBING
J 2
(-5425 3475);
DISPLAY 1.446809 (-5425 3475);
PAINT GREEN (-5425 3475);
DISPLAY INVISIBLE (-5425 3475);
FORCEPROP 1 LAST HDL_TAP TRUE
J 2
(-5750 3300);
DISPLAY 1.446809 (-5750 3300);
PAINT GREEN (-5750 3300);
DISPLAY INVISIBLE (-5750 3300);
FORCEPROP 1 LAST PATH I34
J 2
(-5423 3425);
DISPLAY 0.872340 (-5423 3425);
PAINT GREEN (-5423 3425);
DISPLAY INVISIBLE (-5423 3425);
FORCEADD TAP..1
R 2
(-5425 3525);
FORCEPROP 3 LASTPIN (-5375 3525) SIG_NAME TP_P3E_CPU1_PE2_RSR_RXP<15>
J 0
(-5365 3535);
DISPLAY 0.659574 (-5365 3535);
PAINT MONO (-5365 3535);
DISPLAY INVISIBLE (-5365 3535);
FORCEPROP 1 LASTPIN (-5375 3525) BN 15
J 2
(-5363 3533);
DISPLAY 0.617021 (-5363 3533);
PAINT GREEN (-5363 3533);
FORCEPROP 2 LAST CDS_LIB mstr_standard
J 0
(-5425 3525);
PAINT MONO (-5425 3525);
DISPLAY INVISIBLE (-5425 3525);
FORCEPROP 1 LAST BODY_TYPE PLUMBING
J 2
(-5425 3575);
DISPLAY 1.446809 (-5425 3575);
PAINT GREEN (-5425 3575);
DISPLAY INVISIBLE (-5425 3575);
FORCEPROP 1 LAST HDL_TAP TRUE
J 2
(-5750 3400);
DISPLAY 1.446809 (-5750 3400);
PAINT GREEN (-5750 3400);
DISPLAY INVISIBLE (-5750 3400);
FORCEPROP 1 LAST PATH I35
J 2
(-5423 3525);
DISPLAY 0.872340 (-5423 3525);
PAINT GREEN (-5423 3525);
DISPLAY INVISIBLE (-5423 3525);
FORCEADD TAP..1
(-2950 1975);
FORCEPROP 3 LASTPIN (-3000 1975) SIG_NAME TP_P3E_CPU1_PE2_RSR_TXP<2>
J 0
(-2990 1985);
DISPLAY 0.659574 (-2990 1985);
PAINT MONO (-2990 1985);
DISPLAY INVISIBLE (-2990 1985);
FORCEPROP 1 LASTPIN (-3000 1975) BN 2
J 0
(-3012 1983);
DISPLAY 0.617021 (-3012 1983);
PAINT GREEN (-3012 1983);
FORCEPROP 2 LAST CDS_LIB mstr_standard
J 2
(-2950 1975);
PAINT MONO (-2950 1975);
DISPLAY INVISIBLE (-2950 1975);
FORCEPROP 1 LAST BODY_TYPE PLUMBING
J 0
(-2950 2025);
DISPLAY 1.446809 (-2950 2025);
PAINT GREEN (-2950 2025);
DISPLAY INVISIBLE (-2950 2025);
FORCEPROP 1 LAST HDL_TAP TRUE
J 0
(-2625 1850);
DISPLAY 1.446809 (-2625 1850);
PAINT GREEN (-2625 1850);
DISPLAY INVISIBLE (-2625 1850);
FORCEPROP 1 LAST PATH I36
J 0
(-2952 1975);
DISPLAY 0.872340 (-2952 1975);
PAINT GREEN (-2952 1975);
DISPLAY INVISIBLE (-2952 1975);
FORCEADD TAP..1
(-2950 1875);
FORCEPROP 3 LASTPIN (-3000 1875) SIG_NAME TP_P3E_CPU1_PE2_RSR_TXP<0>
J 0
(-2990 1885);
DISPLAY 0.659574 (-2990 1885);
PAINT MONO (-2990 1885);
DISPLAY INVISIBLE (-2990 1885);
FORCEPROP 1 LASTPIN (-3000 1875) BN 0
J 0
(-3012 1883);
DISPLAY 0.617021 (-3012 1883);
PAINT GREEN (-3012 1883);
FORCEPROP 2 LAST CDS_LIB mstr_standard
J 2
(-2950 1875);
PAINT MONO (-2950 1875);
DISPLAY INVISIBLE (-2950 1875);
FORCEPROP 1 LAST BODY_TYPE PLUMBING
J 0
(-2950 1925);
DISPLAY 1.446809 (-2950 1925);
PAINT GREEN (-2950 1925);
DISPLAY INVISIBLE (-2950 1925);
FORCEPROP 1 LAST HDL_TAP TRUE
J 0
(-2625 1750);
DISPLAY 1.446809 (-2625 1750);
PAINT GREEN (-2625 1750);
DISPLAY INVISIBLE (-2625 1750);
FORCEPROP 1 LAST PATH I37
J 0
(-2952 1875);
DISPLAY 0.872340 (-2952 1875);
PAINT GREEN (-2952 1875);
DISPLAY INVISIBLE (-2952 1875);
FORCEADD TAP..1
(-2950 1925);
FORCEPROP 3 LASTPIN (-3000 1925) SIG_NAME TP_P3E_CPU1_PE2_RSR_TXP<1>
J 0
(-2990 1935);
DISPLAY 0.659574 (-2990 1935);
PAINT MONO (-2990 1935);
DISPLAY INVISIBLE (-2990 1935);
FORCEPROP 1 LASTPIN (-3000 1925) BN 1
J 0
(-3012 1933);
DISPLAY 0.617021 (-3012 1933);
PAINT GREEN (-3012 1933);
FORCEPROP 2 LAST CDS_LIB mstr_standard
J 2
(-2950 1925);
PAINT MONO (-2950 1925);
DISPLAY INVISIBLE (-2950 1925);
FORCEPROP 1 LAST BODY_TYPE PLUMBING
J 0
(-2950 1975);
DISPLAY 1.446809 (-2950 1975);
PAINT GREEN (-2950 1975);
DISPLAY INVISIBLE (-2950 1975);
FORCEPROP 1 LAST HDL_TAP TRUE
J 0
(-2625 1800);
DISPLAY 1.446809 (-2625 1800);
PAINT GREEN (-2625 1800);
DISPLAY INVISIBLE (-2625 1800);
FORCEPROP 1 LAST PATH I38
J 0
(-2952 1925);
DISPLAY 0.872340 (-2952 1925);
PAINT GREEN (-2952 1925);
DISPLAY INVISIBLE (-2952 1925);
FORCEADD TAP..1
(-2800 1675);
FORCEPROP 3 LASTPIN (-2850 1675) SIG_NAME TP_P3E_CPU1_PE2_RSR_TXN<1>
J 0
(-2840 1685);
DISPLAY 0.659574 (-2840 1685);
PAINT MONO (-2840 1685);
DISPLAY INVISIBLE (-2840 1685);
FORCEPROP 1 LASTPIN (-2850 1675) BN 1
J 0
(-2862 1683);
DISPLAY 0.617021 (-2862 1683);
PAINT GREEN (-2862 1683);
FORCEPROP 2 LAST CDS_LIB mstr_standard
J 2
(-2800 1675);
PAINT MONO (-2800 1675);
DISPLAY INVISIBLE (-2800 1675);
FORCEPROP 1 LAST BODY_TYPE PLUMBING
J 0
(-2800 1725);
DISPLAY 1.446809 (-2800 1725);
PAINT GREEN (-2800 1725);
DISPLAY INVISIBLE (-2800 1725);
FORCEPROP 1 LAST HDL_TAP TRUE
J 0
(-2475 1550);
DISPLAY 1.446809 (-2475 1550);
PAINT GREEN (-2475 1550);
DISPLAY INVISIBLE (-2475 1550);
FORCEPROP 1 LAST PATH I39
J 0
(-2802 1675);
DISPLAY 0.872340 (-2802 1675);
PAINT GREEN (-2802 1675);
DISPLAY INVISIBLE (-2802 1675);
FORCEADD TAP..1
R 2
(-5575 1675);
FORCEPROP 3 LASTPIN (-5525 1675) SIG_NAME TP_P3E_CPU1_PE2_RSR_RXN<1>
J 0
(-5515 1685);
DISPLAY 0.659574 (-5515 1685);
PAINT MONO (-5515 1685);
DISPLAY INVISIBLE (-5515 1685);
FORCEPROP 1 LASTPIN (-5525 1675) BN 1
J 2
(-5513 1683);
DISPLAY 0.617021 (-5513 1683);
PAINT GREEN (-5513 1683);
FORCEPROP 2 LAST CDS_LIB mstr_standard
J 0
(-5575 1675);
PAINT MONO (-5575 1675);
DISPLAY INVISIBLE (-5575 1675);
FORCEPROP 1 LAST BODY_TYPE PLUMBING
J 2
(-5575 1725);
DISPLAY 1.446809 (-5575 1725);
PAINT GREEN (-5575 1725);
DISPLAY INVISIBLE (-5575 1725);
FORCEPROP 1 LAST HDL_TAP TRUE
J 2
(-5900 1550);
DISPLAY 1.446809 (-5900 1550);
PAINT GREEN (-5900 1550);
DISPLAY INVISIBLE (-5900 1550);
FORCEPROP 1 LAST PATH I4
J 2
(-5573 1675);
DISPLAY 0.872340 (-5573 1675);
PAINT GREEN (-5573 1675);
DISPLAY INVISIBLE (-5573 1675);
FORCEADD TAP..1
(-2800 1625);
FORCEPROP 3 LASTPIN (-2850 1625) SIG_NAME TP_P3E_CPU1_PE2_RSR_TXN<0>
J 0
(-2840 1635);
DISPLAY 0.659574 (-2840 1635);
PAINT MONO (-2840 1635);
DISPLAY INVISIBLE (-2840 1635);
FORCEPROP 1 LASTPIN (-2850 1625) BN 0
J 0
(-2862 1633);
DISPLAY 0.617021 (-2862 1633);
PAINT GREEN (-2862 1633);
FORCEPROP 2 LAST CDS_LIB mstr_standard
J 2
(-2800 1625);
PAINT MONO (-2800 1625);
DISPLAY INVISIBLE (-2800 1625);
FORCEPROP 1 LAST BODY_TYPE PLUMBING
J 0
(-2800 1675);
DISPLAY 1.446809 (-2800 1675);
PAINT GREEN (-2800 1675);
DISPLAY INVISIBLE (-2800 1675);
FORCEPROP 1 LAST HDL_TAP TRUE
J 0
(-2475 1500);
DISPLAY 1.446809 (-2475 1500);
PAINT GREEN (-2475 1500);
DISPLAY INVISIBLE (-2475 1500);
FORCEPROP 1 LAST PATH I40
J 0
(-2802 1625);
DISPLAY 0.872340 (-2802 1625);
PAINT GREEN (-2802 1625);
DISPLAY INVISIBLE (-2802 1625);
FORCEADD TAP..1
(-2800 1725);
FORCEPROP 3 LASTPIN (-2850 1725) SIG_NAME TP_P3E_CPU1_PE2_RSR_TXN<2>
J 0
(-2840 1735);
DISPLAY 0.659574 (-2840 1735);
PAINT MONO (-2840 1735);
DISPLAY INVISIBLE (-2840 1735);
FORCEPROP 1 LASTPIN (-2850 1725) BN 2
J 0
(-2862 1733);
DISPLAY 0.617021 (-2862 1733);
PAINT GREEN (-2862 1733);
FORCEPROP 2 LAST CDS_LIB mstr_standard
J 2
(-2800 1725);
PAINT MONO (-2800 1725);
DISPLAY INVISIBLE (-2800 1725);
FORCEPROP 1 LAST BODY_TYPE PLUMBING
J 0
(-2800 1775);
DISPLAY 1.446809 (-2800 1775);
PAINT GREEN (-2800 1775);
DISPLAY INVISIBLE (-2800 1775);
FORCEPROP 1 LAST HDL_TAP TRUE
J 0
(-2475 1600);
DISPLAY 1.446809 (-2475 1600);
PAINT GREEN (-2475 1600);
DISPLAY INVISIBLE (-2475 1600);
FORCEPROP 1 LAST PATH I41
J 0
(-2802 1725);
DISPLAY 0.872340 (-2802 1725);
PAINT GREEN (-2802 1725);
DISPLAY INVISIBLE (-2802 1725);
FORCEADD TAP..1
(-2800 1775);
FORCEPROP 3 LASTPIN (-2850 1775) SIG_NAME TP_P3E_CPU1_PE2_RSR_TXN<3>
J 0
(-2840 1785);
DISPLAY 0.659574 (-2840 1785);
PAINT MONO (-2840 1785);
DISPLAY INVISIBLE (-2840 1785);
FORCEPROP 1 LASTPIN (-2850 1775) BN 3
J 0
(-2862 1783);
DISPLAY 0.617021 (-2862 1783);
PAINT GREEN (-2862 1783);
FORCEPROP 2 LAST CDS_LIB mstr_standard
J 2
(-2800 1775);
PAINT MONO (-2800 1775);
DISPLAY INVISIBLE (-2800 1775);
FORCEPROP 1 LAST BODY_TYPE PLUMBING
J 0
(-2800 1825);
DISPLAY 1.446809 (-2800 1825);
PAINT GREEN (-2800 1825);
DISPLAY INVISIBLE (-2800 1825);
FORCEPROP 1 LAST HDL_TAP TRUE
J 0
(-2475 1650);
DISPLAY 1.446809 (-2475 1650);
PAINT GREEN (-2475 1650);
DISPLAY INVISIBLE (-2475 1650);
FORCEPROP 1 LAST PATH I42
J 0
(-2802 1775);
DISPLAY 0.872340 (-2802 1775);
PAINT GREEN (-2802 1775);
DISPLAY INVISIBLE (-2802 1775);
FORCEADD TAP..1
(-2950 2475);
FORCEPROP 3 LASTPIN (-3000 2475) SIG_NAME TP_P3E_CPU1_PE2_RSR_TXP<6>
J 0
(-2990 2485);
DISPLAY 0.659574 (-2990 2485);
PAINT MONO (-2990 2485);
DISPLAY INVISIBLE (-2990 2485);
FORCEPROP 1 LASTPIN (-3000 2475) BN 6
J 0
(-3012 2483);
DISPLAY 0.617021 (-3012 2483);
PAINT GREEN (-3012 2483);
FORCEPROP 2 LAST CDS_LIB mstr_standard
J 2
(-2950 2475);
PAINT MONO (-2950 2475);
DISPLAY INVISIBLE (-2950 2475);
FORCEPROP 1 LAST BODY_TYPE PLUMBING
J 0
(-2950 2525);
DISPLAY 1.446809 (-2950 2525);
PAINT GREEN (-2950 2525);
DISPLAY INVISIBLE (-2950 2525);
FORCEPROP 1 LAST HDL_TAP TRUE
J 0
(-2625 2350);
DISPLAY 1.446809 (-2625 2350);
PAINT GREEN (-2625 2350);
DISPLAY INVISIBLE (-2625 2350);
FORCEPROP 1 LAST PATH I43
J 0
(-2952 2475);
DISPLAY 0.872340 (-2952 2475);
PAINT GREEN (-2952 2475);
DISPLAY INVISIBLE (-2952 2475);
FORCEADD TAP..1
(-2950 2425);
FORCEPROP 3 LASTPIN (-3000 2425) SIG_NAME TP_P3E_CPU1_PE2_RSR_TXP<5>
J 0
(-2990 2435);
DISPLAY 0.659574 (-2990 2435);
PAINT MONO (-2990 2435);
DISPLAY INVISIBLE (-2990 2435);
FORCEPROP 1 LASTPIN (-3000 2425) BN 5
J 0
(-3012 2433);
DISPLAY 0.617021 (-3012 2433);
PAINT GREEN (-3012 2433);
FORCEPROP 2 LAST CDS_LIB mstr_standard
J 2
(-2950 2425);
PAINT MONO (-2950 2425);
DISPLAY INVISIBLE (-2950 2425);
FORCEPROP 1 LAST BODY_TYPE PLUMBING
J 0
(-2950 2475);
DISPLAY 1.446809 (-2950 2475);
PAINT GREEN (-2950 2475);
DISPLAY INVISIBLE (-2950 2475);
FORCEPROP 1 LAST HDL_TAP TRUE
J 0
(-2625 2300);
DISPLAY 1.446809 (-2625 2300);
PAINT GREEN (-2625 2300);
DISPLAY INVISIBLE (-2625 2300);
FORCEPROP 1 LAST PATH I44
J 0
(-2952 2425);
DISPLAY 0.872340 (-2952 2425);
PAINT GREEN (-2952 2425);
DISPLAY INVISIBLE (-2952 2425);
FORCEADD TAP..1
(-2950 2375);
FORCEPROP 3 LASTPIN (-3000 2375) SIG_NAME TP_P3E_CPU1_PE2_RSR_TXP<4>
J 0
(-2990 2385);
DISPLAY 0.659574 (-2990 2385);
PAINT MONO (-2990 2385);
DISPLAY INVISIBLE (-2990 2385);
FORCEPROP 1 LASTPIN (-3000 2375) BN 4
J 0
(-3012 2383);
DISPLAY 0.617021 (-3012 2383);
PAINT GREEN (-3012 2383);
FORCEPROP 2 LAST CDS_LIB mstr_standard
J 2
(-2950 2375);
PAINT MONO (-2950 2375);
DISPLAY INVISIBLE (-2950 2375);
FORCEPROP 1 LAST BODY_TYPE PLUMBING
J 0
(-2950 2425);
DISPLAY 1.446809 (-2950 2425);
PAINT GREEN (-2950 2425);
DISPLAY INVISIBLE (-2950 2425);
FORCEPROP 1 LAST HDL_TAP TRUE
J 0
(-2625 2250);
DISPLAY 1.446809 (-2625 2250);
PAINT GREEN (-2625 2250);
DISPLAY INVISIBLE (-2625 2250);
FORCEPROP 1 LAST PATH I45
J 0
(-2952 2375);
DISPLAY 0.872340 (-2952 2375);
PAINT GREEN (-2952 2375);
DISPLAY INVISIBLE (-2952 2375);
FORCEADD TAP..1
(-2950 2025);
FORCEPROP 3 LASTPIN (-3000 2025) SIG_NAME TP_P3E_CPU1_PE2_RSR_TXP<3>
J 0
(-2990 2035);
DISPLAY 0.659574 (-2990 2035);
PAINT MONO (-2990 2035);
DISPLAY INVISIBLE (-2990 2035);
FORCEPROP 1 LASTPIN (-3000 2025) BN 3
J 0
(-3012 2033);
DISPLAY 0.617021 (-3012 2033);
PAINT GREEN (-3012 2033);
FORCEPROP 2 LAST CDS_LIB mstr_standard
J 2
(-2950 2025);
PAINT MONO (-2950 2025);
DISPLAY INVISIBLE (-2950 2025);
FORCEPROP 1 LAST BODY_TYPE PLUMBING
J 0
(-2950 2075);
DISPLAY 1.446809 (-2950 2075);
PAINT GREEN (-2950 2075);
DISPLAY INVISIBLE (-2950 2075);
FORCEPROP 1 LAST HDL_TAP TRUE
J 0
(-2625 1900);
DISPLAY 1.446809 (-2625 1900);
PAINT GREEN (-2625 1900);
DISPLAY INVISIBLE (-2625 1900);
FORCEPROP 1 LAST PATH I46
J 0
(-2952 2025);
DISPLAY 0.872340 (-2952 2025);
PAINT GREEN (-2952 2025);
DISPLAY INVISIBLE (-2952 2025);
FORCEADD TAP..1
(-2800 2125);
FORCEPROP 3 LASTPIN (-2850 2125) SIG_NAME TP_P3E_CPU1_PE2_RSR_TXN<4>
J 0
(-2840 2135);
DISPLAY 0.659574 (-2840 2135);
PAINT MONO (-2840 2135);
DISPLAY INVISIBLE (-2840 2135);
FORCEPROP 1 LASTPIN (-2850 2125) BN 4
J 0
(-2862 2133);
DISPLAY 0.617021 (-2862 2133);
PAINT GREEN (-2862 2133);
FORCEPROP 2 LAST CDS_LIB mstr_standard
J 2
(-2800 2125);
PAINT MONO (-2800 2125);
DISPLAY INVISIBLE (-2800 2125);
FORCEPROP 1 LAST BODY_TYPE PLUMBING
J 0
(-2800 2175);
DISPLAY 1.446809 (-2800 2175);
PAINT GREEN (-2800 2175);
DISPLAY INVISIBLE (-2800 2175);
FORCEPROP 1 LAST HDL_TAP TRUE
J 0
(-2475 2000);
DISPLAY 1.446809 (-2475 2000);
PAINT GREEN (-2475 2000);
DISPLAY INVISIBLE (-2475 2000);
FORCEPROP 1 LAST PATH I47
J 0
(-2802 2125);
DISPLAY 0.872340 (-2802 2125);
PAINT GREEN (-2802 2125);
DISPLAY INVISIBLE (-2802 2125);
FORCEADD TAP..1
(-2800 2175);
FORCEPROP 3 LASTPIN (-2850 2175) SIG_NAME TP_P3E_CPU1_PE2_RSR_TXN<5>
J 0
(-2840 2185);
DISPLAY 0.659574 (-2840 2185);
PAINT MONO (-2840 2185);
DISPLAY INVISIBLE (-2840 2185);
FORCEPROP 1 LASTPIN (-2850 2175) BN 5
J 0
(-2862 2183);
DISPLAY 0.617021 (-2862 2183);
PAINT GREEN (-2862 2183);
FORCEPROP 2 LAST CDS_LIB mstr_standard
J 2
(-2800 2175);
PAINT MONO (-2800 2175);
DISPLAY INVISIBLE (-2800 2175);
FORCEPROP 1 LAST BODY_TYPE PLUMBING
J 0
(-2800 2225);
DISPLAY 1.446809 (-2800 2225);
PAINT GREEN (-2800 2225);
DISPLAY INVISIBLE (-2800 2225);
FORCEPROP 1 LAST HDL_TAP TRUE
J 0
(-2475 2050);
DISPLAY 1.446809 (-2475 2050);
PAINT GREEN (-2475 2050);
DISPLAY INVISIBLE (-2475 2050);
FORCEPROP 1 LAST PATH I48
J 0
(-2802 2175);
DISPLAY 0.872340 (-2802 2175);
PAINT GREEN (-2802 2175);
DISPLAY INVISIBLE (-2802 2175);
FORCEADD TAP..1
(-2800 2225);
FORCEPROP 3 LASTPIN (-2850 2225) SIG_NAME TP_P3E_CPU1_PE2_RSR_TXN<6>
J 0
(-2840 2235);
DISPLAY 0.659574 (-2840 2235);
PAINT MONO (-2840 2235);
DISPLAY INVISIBLE (-2840 2235);
FORCEPROP 1 LASTPIN (-2850 2225) BN 6
J 0
(-2862 2233);
DISPLAY 0.617021 (-2862 2233);
PAINT GREEN (-2862 2233);
FORCEPROP 2 LAST CDS_LIB mstr_standard
J 2
(-2800 2225);
PAINT MONO (-2800 2225);
DISPLAY INVISIBLE (-2800 2225);
FORCEPROP 1 LAST BODY_TYPE PLUMBING
J 0
(-2800 2275);
DISPLAY 1.446809 (-2800 2275);
PAINT GREEN (-2800 2275);
DISPLAY INVISIBLE (-2800 2275);
FORCEPROP 1 LAST HDL_TAP TRUE
J 0
(-2475 2100);
DISPLAY 1.446809 (-2475 2100);
PAINT GREEN (-2475 2100);
DISPLAY INVISIBLE (-2475 2100);
FORCEPROP 1 LAST PATH I49
J 0
(-2802 2225);
DISPLAY 0.872340 (-2802 2225);
PAINT GREEN (-2802 2225);
DISPLAY INVISIBLE (-2802 2225);
FORCEADD TAP..1
R 2
(-5575 1625);
FORCEPROP 3 LASTPIN (-5525 1625) SIG_NAME TP_P3E_CPU1_PE2_RSR_RXN<0>
J 0
(-5515 1635);
DISPLAY 0.659574 (-5515 1635);
PAINT MONO (-5515 1635);
DISPLAY INVISIBLE (-5515 1635);
FORCEPROP 1 LASTPIN (-5525 1625) BN 0
J 2
(-5513 1633);
DISPLAY 0.617021 (-5513 1633);
PAINT GREEN (-5513 1633);
FORCEPROP 2 LAST CDS_LIB mstr_standard
J 0
(-5575 1625);
PAINT MONO (-5575 1625);
DISPLAY INVISIBLE (-5575 1625);
FORCEPROP 1 LAST BODY_TYPE PLUMBING
J 2
(-5575 1675);
DISPLAY 1.446809 (-5575 1675);
PAINT GREEN (-5575 1675);
DISPLAY INVISIBLE (-5575 1675);
FORCEPROP 1 LAST HDL_TAP TRUE
J 2
(-5900 1500);
DISPLAY 1.446809 (-5900 1500);
PAINT GREEN (-5900 1500);
DISPLAY INVISIBLE (-5900 1500);
FORCEPROP 1 LAST PATH I5
J 2
(-5573 1625);
DISPLAY 0.872340 (-5573 1625);
PAINT GREEN (-5573 1625);
DISPLAY INVISIBLE (-5573 1625);
FORCEADD TAP..1
(-2800 2275);
FORCEPROP 3 LASTPIN (-2850 2275) SIG_NAME TP_P3E_CPU1_PE2_RSR_TXN<7>
J 0
(-2840 2285);
DISPLAY 0.659574 (-2840 2285);
PAINT MONO (-2840 2285);
DISPLAY INVISIBLE (-2840 2285);
FORCEPROP 1 LASTPIN (-2850 2275) BN 7
J 0
(-2862 2283);
DISPLAY 0.617021 (-2862 2283);
PAINT GREEN (-2862 2283);
FORCEPROP 2 LAST CDS_LIB mstr_standard
J 2
(-2800 2275);
PAINT MONO (-2800 2275);
DISPLAY INVISIBLE (-2800 2275);
FORCEPROP 1 LAST BODY_TYPE PLUMBING
J 0
(-2800 2325);
DISPLAY 1.446809 (-2800 2325);
PAINT GREEN (-2800 2325);
DISPLAY INVISIBLE (-2800 2325);
FORCEPROP 1 LAST HDL_TAP TRUE
J 0
(-2475 2150);
DISPLAY 1.446809 (-2475 2150);
PAINT GREEN (-2475 2150);
DISPLAY INVISIBLE (-2475 2150);
FORCEPROP 1 LAST PATH I50
J 0
(-2802 2275);
DISPLAY 0.872340 (-2802 2275);
PAINT GREEN (-2802 2275);
DISPLAY INVISIBLE (-2802 2275);
FORCEADD TAP..1
(-2950 2975);
FORCEPROP 3 LASTPIN (-3000 2975) SIG_NAME TP_P3E_CPU1_PE2_RSR_TXP<10>
J 0
(-2990 2985);
DISPLAY 0.659574 (-2990 2985);
PAINT MONO (-2990 2985);
DISPLAY INVISIBLE (-2990 2985);
FORCEPROP 1 LASTPIN (-3000 2975) BN 10
J 0
(-3012 2983);
DISPLAY 0.617021 (-3012 2983);
PAINT GREEN (-3012 2983);
FORCEPROP 2 LAST CDS_LIB mstr_standard
J 2
(-2950 2975);
PAINT MONO (-2950 2975);
DISPLAY INVISIBLE (-2950 2975);
FORCEPROP 1 LAST BODY_TYPE PLUMBING
J 0
(-2950 3025);
DISPLAY 1.446809 (-2950 3025);
PAINT GREEN (-2950 3025);
DISPLAY INVISIBLE (-2950 3025);
FORCEPROP 1 LAST HDL_TAP TRUE
J 0
(-2625 2850);
DISPLAY 1.446809 (-2625 2850);
PAINT GREEN (-2625 2850);
DISPLAY INVISIBLE (-2625 2850);
FORCEPROP 1 LAST PATH I51
J 0
(-2952 2975);
DISPLAY 0.872340 (-2952 2975);
PAINT GREEN (-2952 2975);
DISPLAY INVISIBLE (-2952 2975);
FORCEADD TAP..1
(-2950 2925);
FORCEPROP 3 LASTPIN (-3000 2925) SIG_NAME TP_P3E_CPU1_PE2_RSR_TXP<9>
J 0
(-2990 2935);
DISPLAY 0.659574 (-2990 2935);
PAINT MONO (-2990 2935);
DISPLAY INVISIBLE (-2990 2935);
FORCEPROP 1 LASTPIN (-3000 2925) BN 9
J 0
(-3012 2933);
DISPLAY 0.617021 (-3012 2933);
PAINT GREEN (-3012 2933);
FORCEPROP 2 LAST CDS_LIB mstr_standard
J 2
(-2950 2925);
PAINT MONO (-2950 2925);
DISPLAY INVISIBLE (-2950 2925);
FORCEPROP 1 LAST BODY_TYPE PLUMBING
J 0
(-2950 2975);
DISPLAY 1.446809 (-2950 2975);
PAINT GREEN (-2950 2975);
DISPLAY INVISIBLE (-2950 2975);
FORCEPROP 1 LAST HDL_TAP TRUE
J 0
(-2625 2800);
DISPLAY 1.446809 (-2625 2800);
PAINT GREEN (-2625 2800);
DISPLAY INVISIBLE (-2625 2800);
FORCEPROP 1 LAST PATH I52
J 0
(-2952 2925);
DISPLAY 0.872340 (-2952 2925);
PAINT GREEN (-2952 2925);
DISPLAY INVISIBLE (-2952 2925);
FORCEADD TAP..1
(-2950 2875);
FORCEPROP 3 LASTPIN (-3000 2875) SIG_NAME TP_P3E_CPU1_PE2_RSR_TXP<8>
J 0
(-2990 2885);
DISPLAY 0.659574 (-2990 2885);
PAINT MONO (-2990 2885);
DISPLAY INVISIBLE (-2990 2885);
FORCEPROP 1 LASTPIN (-3000 2875) BN 8
J 0
(-3012 2883);
DISPLAY 0.617021 (-3012 2883);
PAINT GREEN (-3012 2883);
FORCEPROP 2 LAST CDS_LIB mstr_standard
J 2
(-2950 2875);
PAINT MONO (-2950 2875);
DISPLAY INVISIBLE (-2950 2875);
FORCEPROP 1 LAST BODY_TYPE PLUMBING
J 0
(-2950 2925);
DISPLAY 1.446809 (-2950 2925);
PAINT GREEN (-2950 2925);
DISPLAY INVISIBLE (-2950 2925);
FORCEPROP 1 LAST HDL_TAP TRUE
J 0
(-2625 2750);
DISPLAY 1.446809 (-2625 2750);
PAINT GREEN (-2625 2750);
DISPLAY INVISIBLE (-2625 2750);
FORCEPROP 1 LAST PATH I53
J 0
(-2952 2875);
DISPLAY 0.872340 (-2952 2875);
PAINT GREEN (-2952 2875);
DISPLAY INVISIBLE (-2952 2875);
FORCEADD TAP..1
(-2950 2525);
FORCEPROP 3 LASTPIN (-3000 2525) SIG_NAME TP_P3E_CPU1_PE2_RSR_TXP<7>
J 0
(-2990 2535);
DISPLAY 0.659574 (-2990 2535);
PAINT MONO (-2990 2535);
DISPLAY INVISIBLE (-2990 2535);
FORCEPROP 1 LASTPIN (-3000 2525) BN 7
J 0
(-3012 2533);
DISPLAY 0.617021 (-3012 2533);
PAINT GREEN (-3012 2533);
FORCEPROP 2 LAST CDS_LIB mstr_standard
J 2
(-2950 2525);
PAINT MONO (-2950 2525);
DISPLAY INVISIBLE (-2950 2525);
FORCEPROP 1 LAST BODY_TYPE PLUMBING
J 0
(-2950 2575);
DISPLAY 1.446809 (-2950 2575);
PAINT GREEN (-2950 2575);
DISPLAY INVISIBLE (-2950 2575);
FORCEPROP 1 LAST HDL_TAP TRUE
J 0
(-2625 2400);
DISPLAY 1.446809 (-2625 2400);
PAINT GREEN (-2625 2400);
DISPLAY INVISIBLE (-2625 2400);
FORCEPROP 1 LAST PATH I54
J 0
(-2952 2525);
DISPLAY 0.872340 (-2952 2525);
PAINT GREEN (-2952 2525);
DISPLAY INVISIBLE (-2952 2525);
FORCEADD TAP..1
(-2800 2625);
FORCEPROP 3 LASTPIN (-2850 2625) SIG_NAME TP_P3E_CPU1_PE2_RSR_TXN<8>
J 0
(-2840 2635);
DISPLAY 0.659574 (-2840 2635);
PAINT MONO (-2840 2635);
DISPLAY INVISIBLE (-2840 2635);
FORCEPROP 1 LASTPIN (-2850 2625) BN 8
J 0
(-2862 2633);
DISPLAY 0.617021 (-2862 2633);
PAINT GREEN (-2862 2633);
FORCEPROP 2 LAST CDS_LIB mstr_standard
J 2
(-2800 2625);
PAINT MONO (-2800 2625);
DISPLAY INVISIBLE (-2800 2625);
FORCEPROP 1 LAST BODY_TYPE PLUMBING
J 0
(-2800 2675);
DISPLAY 1.446809 (-2800 2675);
PAINT GREEN (-2800 2675);
DISPLAY INVISIBLE (-2800 2675);
FORCEPROP 1 LAST HDL_TAP TRUE
J 0
(-2475 2500);
DISPLAY 1.446809 (-2475 2500);
PAINT GREEN (-2475 2500);
DISPLAY INVISIBLE (-2475 2500);
FORCEPROP 1 LAST PATH I55
J 0
(-2802 2625);
DISPLAY 0.872340 (-2802 2625);
PAINT GREEN (-2802 2625);
DISPLAY INVISIBLE (-2802 2625);
FORCEADD TAP..1
(-2800 2725);
FORCEPROP 3 LASTPIN (-2850 2725) SIG_NAME TP_P3E_CPU1_PE2_RSR_TXN<10>
J 0
(-2840 2735);
DISPLAY 0.659574 (-2840 2735);
PAINT MONO (-2840 2735);
DISPLAY INVISIBLE (-2840 2735);
FORCEPROP 1 LASTPIN (-2850 2725) BN 10
J 0
(-2862 2733);
DISPLAY 0.617021 (-2862 2733);
PAINT GREEN (-2862 2733);
FORCEPROP 2 LAST CDS_LIB mstr_standard
J 2
(-2800 2725);
PAINT MONO (-2800 2725);
DISPLAY INVISIBLE (-2800 2725);
FORCEPROP 1 LAST BODY_TYPE PLUMBING
J 0
(-2800 2775);
DISPLAY 1.446809 (-2800 2775);
PAINT GREEN (-2800 2775);
DISPLAY INVISIBLE (-2800 2775);
FORCEPROP 1 LAST HDL_TAP TRUE
J 0
(-2475 2600);
DISPLAY 1.446809 (-2475 2600);
PAINT GREEN (-2475 2600);
DISPLAY INVISIBLE (-2475 2600);
FORCEPROP 1 LAST PATH I56
J 0
(-2802 2725);
DISPLAY 0.872340 (-2802 2725);
PAINT GREEN (-2802 2725);
DISPLAY INVISIBLE (-2802 2725);
FORCEADD TAP..1
(-2800 2675);
FORCEPROP 3 LASTPIN (-2850 2675) SIG_NAME TP_P3E_CPU1_PE2_RSR_TXN<9>
J 0
(-2840 2685);
DISPLAY 0.659574 (-2840 2685);
PAINT MONO (-2840 2685);
DISPLAY INVISIBLE (-2840 2685);
FORCEPROP 1 LASTPIN (-2850 2675) BN 9
J 0
(-2862 2683);
DISPLAY 0.617021 (-2862 2683);
PAINT GREEN (-2862 2683);
FORCEPROP 2 LAST CDS_LIB mstr_standard
J 2
(-2800 2675);
PAINT MONO (-2800 2675);
DISPLAY INVISIBLE (-2800 2675);
FORCEPROP 1 LAST BODY_TYPE PLUMBING
J 0
(-2800 2725);
DISPLAY 1.446809 (-2800 2725);
PAINT GREEN (-2800 2725);
DISPLAY INVISIBLE (-2800 2725);
FORCEPROP 1 LAST HDL_TAP TRUE
J 0
(-2475 2550);
DISPLAY 1.446809 (-2475 2550);
PAINT GREEN (-2475 2550);
DISPLAY INVISIBLE (-2475 2550);
FORCEPROP 1 LAST PATH I57
J 0
(-2802 2675);
DISPLAY 0.872340 (-2802 2675);
PAINT GREEN (-2802 2675);
DISPLAY INVISIBLE (-2802 2675);
FORCEADD TAP..1
(-2800 2775);
FORCEPROP 3 LASTPIN (-2850 2775) SIG_NAME TP_P3E_CPU1_PE2_RSR_TXN<11>
J 0
(-2840 2785);
DISPLAY 0.659574 (-2840 2785);
PAINT MONO (-2840 2785);
DISPLAY INVISIBLE (-2840 2785);
FORCEPROP 1 LASTPIN (-2850 2775) BN 11
J 0
(-2862 2783);
DISPLAY 0.617021 (-2862 2783);
PAINT GREEN (-2862 2783);
FORCEPROP 2 LAST CDS_LIB mstr_standard
J 2
(-2800 2775);
PAINT MONO (-2800 2775);
DISPLAY INVISIBLE (-2800 2775);
FORCEPROP 1 LAST BODY_TYPE PLUMBING
J 0
(-2800 2825);
DISPLAY 1.446809 (-2800 2825);
PAINT GREEN (-2800 2825);
DISPLAY INVISIBLE (-2800 2825);
FORCEPROP 1 LAST HDL_TAP TRUE
J 0
(-2475 2650);
DISPLAY 1.446809 (-2475 2650);
PAINT GREEN (-2475 2650);
DISPLAY INVISIBLE (-2475 2650);
FORCEPROP 1 LAST PATH I58
J 0
(-2802 2775);
DISPLAY 0.872340 (-2802 2775);
PAINT GREEN (-2802 2775);
DISPLAY INVISIBLE (-2802 2775);
FORCEADD TAP..1
(-2950 3525);
FORCEPROP 3 LASTPIN (-3000 3525) SIG_NAME TP_P3E_CPU1_PE2_RSR_TXP<15>
J 0
(-2990 3535);
DISPLAY 0.659574 (-2990 3535);
PAINT MONO (-2990 3535);
DISPLAY INVISIBLE (-2990 3535);
FORCEPROP 1 LASTPIN (-3000 3525) BN 15
J 0
(-3012 3533);
DISPLAY 0.617021 (-3012 3533);
PAINT GREEN (-3012 3533);
FORCEPROP 2 LAST CDS_LIB mstr_standard
J 2
(-2950 3525);
PAINT MONO (-2950 3525);
DISPLAY INVISIBLE (-2950 3525);
FORCEPROP 1 LAST BODY_TYPE PLUMBING
J 0
(-2950 3575);
DISPLAY 1.446809 (-2950 3575);
PAINT GREEN (-2950 3575);
DISPLAY INVISIBLE (-2950 3575);
FORCEPROP 1 LAST HDL_TAP TRUE
J 0
(-2625 3400);
DISPLAY 1.446809 (-2625 3400);
PAINT GREEN (-2625 3400);
DISPLAY INVISIBLE (-2625 3400);
FORCEPROP 1 LAST PATH I59
J 0
(-2952 3525);
DISPLAY 0.872340 (-2952 3525);
PAINT GREEN (-2952 3525);
DISPLAY INVISIBLE (-2952 3525);
FORCEADD TAP..1
R 2
(-5575 1775);
FORCEPROP 3 LASTPIN (-5525 1775) SIG_NAME TP_P3E_CPU1_PE2_RSR_RXN<3>
J 0
(-5515 1785);
DISPLAY 0.659574 (-5515 1785);
PAINT MONO (-5515 1785);
DISPLAY INVISIBLE (-5515 1785);
FORCEPROP 1 LASTPIN (-5525 1775) BN 3
J 2
(-5513 1783);
DISPLAY 0.617021 (-5513 1783);
PAINT GREEN (-5513 1783);
FORCEPROP 2 LAST CDS_LIB mstr_standard
J 0
(-5575 1775);
PAINT MONO (-5575 1775);
DISPLAY INVISIBLE (-5575 1775);
FORCEPROP 1 LAST BODY_TYPE PLUMBING
J 2
(-5575 1825);
DISPLAY 1.446809 (-5575 1825);
PAINT GREEN (-5575 1825);
DISPLAY INVISIBLE (-5575 1825);
FORCEPROP 1 LAST HDL_TAP TRUE
J 2
(-5900 1650);
DISPLAY 1.446809 (-5900 1650);
PAINT GREEN (-5900 1650);
DISPLAY INVISIBLE (-5900 1650);
FORCEPROP 1 LAST PATH I6
J 2
(-5573 1775);
DISPLAY 0.872340 (-5573 1775);
PAINT GREEN (-5573 1775);
DISPLAY INVISIBLE (-5573 1775);
FORCEADD TAP..1
(-2950 3475);
FORCEPROP 3 LASTPIN (-3000 3475) SIG_NAME TP_P3E_CPU1_PE2_RSR_TXP<14>
J 0
(-2990 3485);
DISPLAY 0.659574 (-2990 3485);
PAINT MONO (-2990 3485);
DISPLAY INVISIBLE (-2990 3485);
FORCEPROP 1 LASTPIN (-3000 3475) BN 14
J 0
(-3012 3483);
DISPLAY 0.617021 (-3012 3483);
PAINT GREEN (-3012 3483);
FORCEPROP 2 LAST CDS_LIB mstr_standard
J 2
(-2950 3475);
PAINT MONO (-2950 3475);
DISPLAY INVISIBLE (-2950 3475);
FORCEPROP 1 LAST BODY_TYPE PLUMBING
J 0
(-2950 3525);
DISPLAY 1.446809 (-2950 3525);
PAINT GREEN (-2950 3525);
DISPLAY INVISIBLE (-2950 3525);
FORCEPROP 1 LAST HDL_TAP TRUE
J 0
(-2625 3350);
DISPLAY 1.446809 (-2625 3350);
PAINT GREEN (-2625 3350);
DISPLAY INVISIBLE (-2625 3350);
FORCEPROP 1 LAST PATH I60
J 0
(-2952 3475);
DISPLAY 0.872340 (-2952 3475);
PAINT GREEN (-2952 3475);
DISPLAY INVISIBLE (-2952 3475);
FORCEADD TAP..1
(-2950 3425);
FORCEPROP 3 LASTPIN (-3000 3425) SIG_NAME TP_P3E_CPU1_PE2_RSR_TXP<13>
J 0
(-2990 3435);
DISPLAY 0.659574 (-2990 3435);
PAINT MONO (-2990 3435);
DISPLAY INVISIBLE (-2990 3435);
FORCEPROP 1 LASTPIN (-3000 3425) BN 13
J 0
(-3012 3433);
DISPLAY 0.617021 (-3012 3433);
PAINT GREEN (-3012 3433);
FORCEPROP 2 LAST CDS_LIB mstr_standard
J 2
(-2950 3425);
PAINT MONO (-2950 3425);
DISPLAY INVISIBLE (-2950 3425);
FORCEPROP 1 LAST BODY_TYPE PLUMBING
J 0
(-2950 3475);
DISPLAY 1.446809 (-2950 3475);
PAINT GREEN (-2950 3475);
DISPLAY INVISIBLE (-2950 3475);
FORCEPROP 1 LAST HDL_TAP TRUE
J 0
(-2625 3300);
DISPLAY 1.446809 (-2625 3300);
PAINT GREEN (-2625 3300);
DISPLAY INVISIBLE (-2625 3300);
FORCEPROP 1 LAST PATH I61
J 0
(-2952 3425);
DISPLAY 0.872340 (-2952 3425);
PAINT GREEN (-2952 3425);
DISPLAY INVISIBLE (-2952 3425);
FORCEADD TAP..1
(-2950 3375);
FORCEPROP 3 LASTPIN (-3000 3375) SIG_NAME TP_P3E_CPU1_PE2_RSR_TXP<12>
J 0
(-2990 3385);
DISPLAY 0.659574 (-2990 3385);
PAINT MONO (-2990 3385);
DISPLAY INVISIBLE (-2990 3385);
FORCEPROP 1 LASTPIN (-3000 3375) BN 12
J 0
(-3012 3383);
DISPLAY 0.617021 (-3012 3383);
PAINT GREEN (-3012 3383);
FORCEPROP 2 LAST CDS_LIB mstr_standard
J 2
(-2950 3375);
PAINT MONO (-2950 3375);
DISPLAY INVISIBLE (-2950 3375);
FORCEPROP 1 LAST BODY_TYPE PLUMBING
J 0
(-2950 3425);
DISPLAY 1.446809 (-2950 3425);
PAINT GREEN (-2950 3425);
DISPLAY INVISIBLE (-2950 3425);
FORCEPROP 1 LAST HDL_TAP TRUE
J 0
(-2625 3250);
DISPLAY 1.446809 (-2625 3250);
PAINT GREEN (-2625 3250);
DISPLAY INVISIBLE (-2625 3250);
FORCEPROP 1 LAST PATH I62
J 0
(-2952 3375);
DISPLAY 0.872340 (-2952 3375);
PAINT GREEN (-2952 3375);
DISPLAY INVISIBLE (-2952 3375);
FORCEADD TAP..1
(-2950 3025);
FORCEPROP 3 LASTPIN (-3000 3025) SIG_NAME TP_P3E_CPU1_PE2_RSR_TXP<11>
J 0
(-2990 3035);
DISPLAY 0.659574 (-2990 3035);
PAINT MONO (-2990 3035);
DISPLAY INVISIBLE (-2990 3035);
FORCEPROP 1 LASTPIN (-3000 3025) BN 11
J 0
(-3012 3033);
DISPLAY 0.617021 (-3012 3033);
PAINT GREEN (-3012 3033);
FORCEPROP 2 LAST CDS_LIB mstr_standard
J 2
(-2950 3025);
PAINT MONO (-2950 3025);
DISPLAY INVISIBLE (-2950 3025);
FORCEPROP 1 LAST BODY_TYPE PLUMBING
J 0
(-2950 3075);
DISPLAY 1.446809 (-2950 3075);
PAINT GREEN (-2950 3075);
DISPLAY INVISIBLE (-2950 3075);
FORCEPROP 1 LAST HDL_TAP TRUE
J 0
(-2625 2900);
DISPLAY 1.446809 (-2625 2900);
PAINT GREEN (-2625 2900);
DISPLAY INVISIBLE (-2625 2900);
FORCEPROP 1 LAST PATH I63
J 0
(-2952 3025);
DISPLAY 0.872340 (-2952 3025);
PAINT GREEN (-2952 3025);
DISPLAY INVISIBLE (-2952 3025);
FORCEADD TAP..1
(-2800 3125);
FORCEPROP 3 LASTPIN (-2850 3125) SIG_NAME TP_P3E_CPU1_PE2_RSR_TXN<12>
J 0
(-2840 3135);
DISPLAY 0.659574 (-2840 3135);
PAINT MONO (-2840 3135);
DISPLAY INVISIBLE (-2840 3135);
FORCEPROP 1 LASTPIN (-2850 3125) BN 12
J 0
(-2862 3133);
DISPLAY 0.617021 (-2862 3133);
PAINT GREEN (-2862 3133);
FORCEPROP 2 LAST CDS_LIB mstr_standard
J 2
(-2800 3125);
PAINT MONO (-2800 3125);
DISPLAY INVISIBLE (-2800 3125);
FORCEPROP 1 LAST BODY_TYPE PLUMBING
J 0
(-2800 3175);
DISPLAY 1.446809 (-2800 3175);
PAINT GREEN (-2800 3175);
DISPLAY INVISIBLE (-2800 3175);
FORCEPROP 1 LAST HDL_TAP TRUE
J 0
(-2475 3000);
DISPLAY 1.446809 (-2475 3000);
PAINT GREEN (-2475 3000);
DISPLAY INVISIBLE (-2475 3000);
FORCEPROP 1 LAST PATH I64
J 0
(-2802 3125);
DISPLAY 0.872340 (-2802 3125);
PAINT GREEN (-2802 3125);
DISPLAY INVISIBLE (-2802 3125);
FORCEADD TAP..1
(-2800 3175);
FORCEPROP 3 LASTPIN (-2850 3175) SIG_NAME TP_P3E_CPU1_PE2_RSR_TXN<13>
J 0
(-2840 3185);
DISPLAY 0.659574 (-2840 3185);
PAINT MONO (-2840 3185);
DISPLAY INVISIBLE (-2840 3185);
FORCEPROP 1 LASTPIN (-2850 3175) BN 13
J 0
(-2862 3183);
DISPLAY 0.617021 (-2862 3183);
PAINT GREEN (-2862 3183);
FORCEPROP 2 LAST CDS_LIB mstr_standard
J 2
(-2800 3175);
PAINT MONO (-2800 3175);
DISPLAY INVISIBLE (-2800 3175);
FORCEPROP 1 LAST BODY_TYPE PLUMBING
J 0
(-2800 3225);
DISPLAY 1.446809 (-2800 3225);
PAINT GREEN (-2800 3225);
DISPLAY INVISIBLE (-2800 3225);
FORCEPROP 1 LAST HDL_TAP TRUE
J 0
(-2475 3050);
DISPLAY 1.446809 (-2475 3050);
PAINT GREEN (-2475 3050);
DISPLAY INVISIBLE (-2475 3050);
FORCEPROP 1 LAST PATH I65
J 0
(-2802 3175);
DISPLAY 0.872340 (-2802 3175);
PAINT GREEN (-2802 3175);
DISPLAY INVISIBLE (-2802 3175);
FORCEADD TAP..1
(-2800 3275);
FORCEPROP 3 LASTPIN (-2850 3275) SIG_NAME TP_P3E_CPU1_PE2_RSR_TXN<15>
J 0
(-2840 3285);
DISPLAY 0.659574 (-2840 3285);
PAINT MONO (-2840 3285);
DISPLAY INVISIBLE (-2840 3285);
FORCEPROP 1 LASTPIN (-2850 3275) BN 15
J 0
(-2862 3283);
DISPLAY 0.617021 (-2862 3283);
PAINT GREEN (-2862 3283);
FORCEPROP 2 LAST CDS_LIB mstr_standard
J 2
(-2800 3275);
PAINT MONO (-2800 3275);
DISPLAY INVISIBLE (-2800 3275);
FORCEPROP 1 LAST BODY_TYPE PLUMBING
J 0
(-2800 3325);
DISPLAY 1.446809 (-2800 3325);
PAINT GREEN (-2800 3325);
DISPLAY INVISIBLE (-2800 3325);
FORCEPROP 1 LAST HDL_TAP TRUE
J 0
(-2475 3150);
DISPLAY 1.446809 (-2475 3150);
PAINT GREEN (-2475 3150);
DISPLAY INVISIBLE (-2475 3150);
FORCEPROP 1 LAST PATH I66
J 0
(-2802 3275);
DISPLAY 0.872340 (-2802 3275);
PAINT GREEN (-2802 3275);
DISPLAY INVISIBLE (-2802 3275);
FORCEADD TAP..1
(-2800 3225);
FORCEPROP 3 LASTPIN (-2850 3225) SIG_NAME TP_P3E_CPU1_PE2_RSR_TXN<14>
J 0
(-2840 3235);
DISPLAY 0.659574 (-2840 3235);
PAINT MONO (-2840 3235);
DISPLAY INVISIBLE (-2840 3235);
FORCEPROP 1 LASTPIN (-2850 3225) BN 14
J 0
(-2862 3233);
DISPLAY 0.617021 (-2862 3233);
PAINT GREEN (-2862 3233);
FORCEPROP 2 LAST CDS_LIB mstr_standard
J 2
(-2800 3225);
PAINT MONO (-2800 3225);
DISPLAY INVISIBLE (-2800 3225);
FORCEPROP 1 LAST BODY_TYPE PLUMBING
J 0
(-2800 3275);
DISPLAY 1.446809 (-2800 3275);
PAINT GREEN (-2800 3275);
DISPLAY INVISIBLE (-2800 3275);
FORCEPROP 1 LAST HDL_TAP TRUE
J 0
(-2475 3100);
DISPLAY 1.446809 (-2475 3100);
PAINT GREEN (-2475 3100);
DISPLAY INVISIBLE (-2475 3100);
FORCEPROP 1 LAST PATH I67
J 0
(-2802 3225);
DISPLAY 0.872340 (-2802 3225);
PAINT GREEN (-2802 3225);
DISPLAY INVISIBLE (-2802 3225);
FORCEADD SKX_EXT_B..11
(-4150 2575);
FORCEPROP 1 LAST LOCATION U2D1
J 0
(-4850 3775);
DISPLAY 0.617021 (-4850 3775);
PAINT AQUA (-4850 3775);
FORCEPROP 1 LAST PART_NUMBER TBD
J 0
(-4850 1425);
DISPLAY 0.617021 (-4850 1425);
PAINT BLUE (-4850 1425);
FORCEPROP 1 LAST MATERIAL IC
J 0
(-4850 3725);
DISPLAY 0.617021 (-4850 3725);
PAINT SKYBLUE (-4850 3725);
FORCEPROP 2 LASTPIN (-3400 3525) $PN BK5
J 0
(-3390 3535);
DISPLAY 0.617021 (-3390 3535);
PAINT ORANGE (-3390 3535);
FORCEPROP 2 LASTPIN (-3400 3475) $PN BM3
J 0
(-3390 3485);
DISPLAY 0.617021 (-3390 3485);
PAINT ORANGE (-3390 3485);
FORCEPROP 2 LASTPIN (-3400 3425) $PN BN4
J 0
(-3390 3435);
DISPLAY 0.617021 (-3390 3435);
PAINT ORANGE (-3390 3435);
FORCEPROP 2 LASTPIN (-3400 3375) $PN BR4
J 0
(-3390 3385);
DISPLAY 0.617021 (-3390 3385);
PAINT ORANGE (-3390 3385);
FORCEPROP 2 LASTPIN (-3400 3025) $PN BV3
J 0
(-3390 3035);
DISPLAY 0.617021 (-3390 3035);
PAINT ORANGE (-3390 3035);
FORCEPROP 2 LASTPIN (-3400 2975) $PN BY5
J 0
(-3390 2985);
DISPLAY 0.617021 (-3390 2985);
PAINT ORANGE (-3390 2985);
FORCEPROP 2 LASTPIN (-3400 2925) $PN BY3
J 0
(-3390 2935);
DISPLAY 0.617021 (-3390 2935);
PAINT ORANGE (-3390 2935);
FORCEPROP 2 LASTPIN (-3400 2875) $PN CD3
J 0
(-3390 2885);
DISPLAY 0.617021 (-3390 2885);
PAINT ORANGE (-3390 2885);
FORCEPROP 2 LASTPIN (-3400 2525) $PN CE4
J 0
(-3390 2535);
DISPLAY 0.617021 (-3390 2535);
PAINT ORANGE (-3390 2535);
FORCEPROP 2 LASTPIN (-3400 2475) $PN CE2
J 0
(-3390 2485);
DISPLAY 0.617021 (-3390 2485);
PAINT ORANGE (-3390 2485);
FORCEPROP 2 LASTPIN (-3400 2425) $PN CK3
J 0
(-3390 2435);
DISPLAY 0.617021 (-3390 2435);
PAINT ORANGE (-3390 2435);
FORCEPROP 2 LASTPIN (-3400 2375) $PN CK1
J 0
(-3390 2385);
DISPLAY 0.617021 (-3390 2385);
PAINT ORANGE (-3390 2385);
FORCEPROP 2 LASTPIN (-3400 2025) $PN CP3
J 0
(-3390 2035);
DISPLAY 0.617021 (-3390 2035);
PAINT ORANGE (-3390 2035);
FORCEPROP 2 LASTPIN (-3400 1975) $PN CR2
J 0
(-3390 1985);
DISPLAY 0.617021 (-3390 1985);
PAINT ORANGE (-3390 1985);
FORCEPROP 2 LASTPIN (-3400 1925) $PN CU2
J 0
(-3390 1935);
DISPLAY 0.617021 (-3390 1935);
PAINT ORANGE (-3390 1935);
FORCEPROP 2 LASTPIN (-3400 1875) $PN CW4
J 0
(-3390 1885);
DISPLAY 0.617021 (-3390 1885);
PAINT ORANGE (-3390 1885);
FORCEPROP 2 LASTPIN (-3400 3275) $PN BM5
J 0
(-3390 3285);
DISPLAY 0.617021 (-3390 3285);
PAINT ORANGE (-3390 3285);
FORCEPROP 2 LASTPIN (-3400 3225) $PN BL4
J 0
(-3390 3235);
DISPLAY 0.617021 (-3390 3235);
PAINT ORANGE (-3390 3235);
FORCEPROP 2 LASTPIN (-3400 3175) $PN BP5
J 0
(-3390 3185);
DISPLAY 0.617021 (-3390 3185);
PAINT ORANGE (-3390 3185);
FORCEPROP 2 LASTPIN (-3400 3125) $PN BU4
J 0
(-3390 3135);
DISPLAY 0.617021 (-3390 3135);
PAINT ORANGE (-3390 3135);
FORCEPROP 2 LASTPIN (-3400 2775) $PN BW4
J 0
(-3390 2785);
DISPLAY 0.617021 (-3390 2785);
PAINT ORANGE (-3390 2785);
FORCEPROP 2 LASTPIN (-3400 2725) $PN CA4
J 0
(-3390 2735);
DISPLAY 0.617021 (-3390 2735);
PAINT ORANGE (-3390 2735);
FORCEPROP 2 LASTPIN (-3400 2675) $PN CB3
J 0
(-3390 2685);
DISPLAY 0.617021 (-3390 2685);
PAINT ORANGE (-3390 2685);
FORCEPROP 2 LASTPIN (-3400 2625) $PN CC2
J 0
(-3390 2635);
DISPLAY 0.617021 (-3390 2635);
PAINT ORANGE (-3390 2635);
FORCEPROP 2 LASTPIN (-3400 2275) $PN CF3
J 0
(-3390 2285);
DISPLAY 0.617021 (-3390 2285);
PAINT ORANGE (-3390 2285);
FORCEPROP 2 LASTPIN (-3400 2225) $PN CG2
J 0
(-3390 2235);
DISPLAY 0.617021 (-3390 2235);
PAINT ORANGE (-3390 2235);
FORCEPROP 2 LASTPIN (-3400 2175) $PN CL2
J 0
(-3390 2185);
DISPLAY 0.617021 (-3390 2185);
PAINT ORANGE (-3390 2185);
FORCEPROP 2 LASTPIN (-3400 2125) $PN CM1
J 0
(-3390 2135);
DISPLAY 0.617021 (-3390 2135);
PAINT ORANGE (-3390 2135);
FORCEPROP 2 LASTPIN (-3400 1775) $PN CT3
J 0
(-3390 1785);
DISPLAY 0.617021 (-3390 1785);
PAINT ORANGE (-3390 1785);
FORCEPROP 2 LASTPIN (-3400 1725) $PN CT1
J 0
(-3390 1735);
DISPLAY 0.617021 (-3390 1735);
PAINT ORANGE (-3390 1735);
FORCEPROP 2 LASTPIN (-3400 1675) $PN CV3
J 0
(-3390 1685);
DISPLAY 0.617021 (-3390 1685);
PAINT ORANGE (-3390 1685);
FORCEPROP 2 LASTPIN (-3400 1625) $PN CY3
J 0
(-3390 1635);
DISPLAY 0.617021 (-3390 1635);
PAINT ORANGE (-3390 1635);
FORCEPROP 2 LASTPIN (-4900 3525) $PN BJ10
J 2
(-4910 3535);
DISPLAY 0.617021 (-4910 3535);
PAINT ORANGE (-4910 3535);
FORCEPROP 2 LASTPIN (-4900 3475) $PN BJ8
J 2
(-4910 3485);
DISPLAY 0.617021 (-4910 3485);
PAINT ORANGE (-4910 3485);
FORCEPROP 2 LASTPIN (-4900 3425) $PN BM7
J 2
(-4910 3435);
DISPLAY 0.617021 (-4910 3435);
PAINT ORANGE (-4910 3435);
FORCEPROP 2 LASTPIN (-4900 3375) $PN BP9
J 2
(-4910 3385);
DISPLAY 0.617021 (-4910 3385);
PAINT ORANGE (-4910 3385);
FORCEPROP 2 LASTPIN (-4900 3025) $PN BP7
J 2
(-4910 3035);
DISPLAY 0.617021 (-4910 3035);
PAINT ORANGE (-4910 3035);
FORCEPROP 2 LASTPIN (-4900 2975) $PN BU6
J 2
(-4910 2985);
DISPLAY 0.617021 (-4910 2985);
PAINT ORANGE (-4910 2985);
FORCEPROP 2 LASTPIN (-4900 2925) $PN BW8
J 2
(-4910 2935);
DISPLAY 0.617021 (-4910 2935);
PAINT ORANGE (-4910 2935);
FORCEPROP 2 LASTPIN (-4900 2875) $PN BV9
J 2
(-4910 2885);
DISPLAY 0.617021 (-4910 2885);
PAINT ORANGE (-4910 2885);
FORCEPROP 2 LASTPIN (-4900 2525) $PN CC8
J 2
(-4910 2535);
DISPLAY 0.617021 (-4910 2535);
PAINT ORANGE (-4910 2535);
FORCEPROP 2 LASTPIN (-4900 2475) $PN CD7
J 2
(-4910 2485);
DISPLAY 0.617021 (-4910 2485);
PAINT ORANGE (-4910 2485);
FORCEPROP 2 LASTPIN (-4900 2425) $PN CF7
J 2
(-4910 2435);
DISPLAY 0.617021 (-4910 2435);
PAINT ORANGE (-4910 2435);
FORCEPROP 2 LASTPIN (-4900 2375) $PN CH7
J 2
(-4910 2385);
DISPLAY 0.617021 (-4910 2385);
PAINT ORANGE (-4910 2385);
FORCEPROP 2 LASTPIN (-4900 2025) $PN CL6
J 2
(-4910 2035);
DISPLAY 0.617021 (-4910 2035);
PAINT ORANGE (-4910 2035);
FORCEPROP 2 LASTPIN (-4900 1975) $PN CN8
J 2
(-4910 1985);
DISPLAY 0.617021 (-4910 1985);
PAINT ORANGE (-4910 1985);
FORCEPROP 2 LASTPIN (-4900 1925) $PN CM9
J 2
(-4910 1935);
DISPLAY 0.617021 (-4910 1935);
PAINT ORANGE (-4910 1935);
FORCEPROP 2 LASTPIN (-4900 1875) $PN CR8
J 2
(-4910 1885);
DISPLAY 0.617021 (-4910 1885);
PAINT ORANGE (-4910 1885);
FORCEPROP 2 LASTPIN (-4900 3275) $PN BK9
J 2
(-4910 3285);
DISPLAY 0.617021 (-4910 3285);
PAINT ORANGE (-4910 3285);
FORCEPROP 2 LASTPIN (-4900 3225) $PN BL8
J 2
(-4910 3235);
DISPLAY 0.617021 (-4910 3235);
PAINT ORANGE (-4910 3235);
FORCEPROP 2 LASTPIN (-4900 3175) $PN BN8
J 2
(-4910 3185);
DISPLAY 0.617021 (-4910 3185);
PAINT ORANGE (-4910 3185);
FORCEPROP 2 LASTPIN (-4900 3125) $PN BR8
J 2
(-4910 3135);
DISPLAY 0.617021 (-4910 3135);
PAINT ORANGE (-4910 3135);
FORCEPROP 2 LASTPIN (-4900 2775) $PN BT7
J 2
(-4910 2785);
DISPLAY 0.617021 (-4910 2785);
PAINT ORANGE (-4910 2785);
FORCEPROP 2 LASTPIN (-4900 2725) $PN BV7
J 2
(-4910 2735);
DISPLAY 0.617021 (-4910 2735);
PAINT ORANGE (-4910 2735);
FORCEPROP 2 LASTPIN (-4900 2675) $PN BY7
J 2
(-4910 2685);
DISPLAY 0.617021 (-4910 2685);
PAINT ORANGE (-4910 2685);
FORCEPROP 2 LASTPIN (-4900 2625) $PN BY9
J 2
(-4910 2635);
DISPLAY 0.617021 (-4910 2635);
PAINT ORANGE (-4910 2635);
FORCEPROP 2 LASTPIN (-4900 2275) $PN CE8
J 2
(-4910 2285);
DISPLAY 0.617021 (-4910 2285);
PAINT ORANGE (-4910 2285);
FORCEPROP 2 LASTPIN (-4900 2225) $PN CE6
J 2
(-4910 2235);
DISPLAY 0.617021 (-4910 2235);
PAINT ORANGE (-4910 2235);
FORCEPROP 2 LASTPIN (-4900 2175) $PN CG8
J 2
(-4910 2185);
DISPLAY 0.617021 (-4910 2185);
PAINT ORANGE (-4910 2185);
FORCEPROP 2 LASTPIN (-4900 2125) $PN CK7
J 2
(-4910 2135);
DISPLAY 0.617021 (-4910 2135);
PAINT ORANGE (-4910 2135);
FORCEPROP 2 LASTPIN (-4900 1775) $PN CM7
J 2
(-4910 1785);
DISPLAY 0.617021 (-4910 1785);
PAINT ORANGE (-4910 1785);
FORCEPROP 2 LASTPIN (-4900 1725) $PN CP7
J 2
(-4910 1735);
DISPLAY 0.617021 (-4910 1735);
PAINT ORANGE (-4910 1735);
FORCEPROP 2 LASTPIN (-4900 1675) $PN CP9
J 2
(-4910 1685);
DISPLAY 0.617021 (-4910 1685);
PAINT ORANGE (-4910 1685);
FORCEPROP 2 LASTPIN (-4900 1625) $PN CT9
J 2
(-4910 1635);
DISPLAY 0.617021 (-4910 1635);
PAINT ORANGE (-4910 1635);
FORCEPROP 1 LAST PACK_TYPE BGA1
J 0
(-4850 3825);
PAINT SKYBLUE (-4850 3825);
DISPLAY INVISIBLE (-4850 3825);
FORCEPROP 2 LAST SEC_TYPE BGA1
J 0
(-4850 3825);
DISPLAY 1.021277 (-4850 3825);
PAINT ORANGE (-4850 3825);
DISPLAY INVISIBLE (-4850 3825);
FORCEPROP 2 LAST CDS_LIB chpset_lib
J 0
(-4150 2575);
PAINT ORANGE (-4150 2575);
DISPLAY INVISIBLE (-4150 2575);
FORCEPROP 2 LAST SEC 11
J 0
(-4850 3825);
DISPLAY 0.680851 (-4850 3825);
PAINT MONO (-4850 3825);
DISPLAY INVISIBLE (-4850 3825);
FORCEPROP 2 LAST CDS_LOCATION U2D1
J 0
(-4850 3775);
DISPLAY 0.617021 (-4850 3775);
PAINT AQUA (-4850 3775);
DISPLAY INVISIBLE (-4850 3775);
FORCEPROP 1 LAST PATH I68
J 0
(-4150 3725);
PAINT GREEN (-4150 3725);
DISPLAY INVISIBLE (-4150 3725);
FORCEADD TAP..1
R 2
(-5425 1975);
FORCEPROP 3 LASTPIN (-5375 1975) SIG_NAME TP_P3E_CPU1_PE2_RSR_RXP<2>
J 0
(-5365 1985);
DISPLAY 0.659574 (-5365 1985);
PAINT MONO (-5365 1985);
DISPLAY INVISIBLE (-5365 1985);
FORCEPROP 1 LASTPIN (-5375 1975) BN 2
J 2
(-5363 1983);
DISPLAY 0.617021 (-5363 1983);
PAINT GREEN (-5363 1983);
FORCEPROP 2 LAST CDS_LIB mstr_standard
J 0
(-5425 1975);
PAINT MONO (-5425 1975);
DISPLAY INVISIBLE (-5425 1975);
FORCEPROP 1 LAST BODY_TYPE PLUMBING
J 2
(-5425 2025);
DISPLAY 1.446809 (-5425 2025);
PAINT GREEN (-5425 2025);
DISPLAY INVISIBLE (-5425 2025);
FORCEPROP 1 LAST HDL_TAP TRUE
J 2
(-5750 1850);
DISPLAY 1.446809 (-5750 1850);
PAINT GREEN (-5750 1850);
DISPLAY INVISIBLE (-5750 1850);
FORCEPROP 1 LAST PATH I7
J 2
(-5423 1975);
DISPLAY 0.872340 (-5423 1975);
PAINT GREEN (-5423 1975);
DISPLAY INVISIBLE (-5423 1975);
FORCEADD TAP..1
R 2
(-5425 1925);
FORCEPROP 3 LASTPIN (-5375 1925) SIG_NAME TP_P3E_CPU1_PE2_RSR_RXP<1>
J 0
(-5365 1935);
DISPLAY 0.659574 (-5365 1935);
PAINT MONO (-5365 1935);
DISPLAY INVISIBLE (-5365 1935);
FORCEPROP 1 LASTPIN (-5375 1925) BN 1
J 2
(-5363 1933);
DISPLAY 0.617021 (-5363 1933);
PAINT GREEN (-5363 1933);
FORCEPROP 2 LAST CDS_LIB mstr_standard
J 0
(-5425 1925);
PAINT MONO (-5425 1925);
DISPLAY INVISIBLE (-5425 1925);
FORCEPROP 1 LAST BODY_TYPE PLUMBING
J 2
(-5425 1975);
DISPLAY 1.446809 (-5425 1975);
PAINT GREEN (-5425 1975);
DISPLAY INVISIBLE (-5425 1975);
FORCEPROP 1 LAST HDL_TAP TRUE
J 2
(-5750 1800);
DISPLAY 1.446809 (-5750 1800);
PAINT GREEN (-5750 1800);
DISPLAY INVISIBLE (-5750 1800);
FORCEPROP 1 LAST PATH I8
J 2
(-5423 1925);
DISPLAY 0.872340 (-5423 1925);
PAINT GREEN (-5423 1925);
DISPLAY INVISIBLE (-5423 1925);
FORCEADD TAP..1
R 2
(-5425 1875);
FORCEPROP 3 LASTPIN (-5375 1875) SIG_NAME TP_P3E_CPU1_PE2_RSR_RXP<0>
J 0
(-5365 1885);
DISPLAY 0.659574 (-5365 1885);
PAINT MONO (-5365 1885);
DISPLAY INVISIBLE (-5365 1885);
FORCEPROP 1 LASTPIN (-5375 1875) BN 0
J 2
(-5363 1883);
DISPLAY 0.617021 (-5363 1883);
PAINT GREEN (-5363 1883);
FORCEPROP 2 LAST CDS_LIB mstr_standard
J 0
(-5425 1875);
PAINT MONO (-5425 1875);
DISPLAY INVISIBLE (-5425 1875);
FORCEPROP 1 LAST BODY_TYPE PLUMBING
J 2
(-5425 1925);
DISPLAY 1.446809 (-5425 1925);
PAINT GREEN (-5425 1925);
DISPLAY INVISIBLE (-5425 1925);
FORCEPROP 1 LAST HDL_TAP TRUE
J 2
(-5750 1750);
DISPLAY 1.446809 (-5750 1750);
PAINT GREEN (-5750 1750);
DISPLAY INVISIBLE (-5750 1750);
FORCEPROP 1 LAST PATH I9
J 2
(-5423 1875);
DISPLAY 0.872340 (-5423 1875);
PAINT GREEN (-5423 1875);
DISPLAY INVISIBLE (-5423 1875);
FORCEADD DESIGN_NOTE..1
(-4650 1325);
FORCEPROP 0 LAST L1 CPU SYMBOLS 1-30 ARE PRELIMINARY AND SUBJECT TO CHANGE
J 0
(-4850 1200);
DISPLAY 1.021277 (-4850 1200);
PAINT ORANGE (-4850 1200);
FORCEPROP 2 LAST CDS_LIB mstr_symbols
J 0
(-4650 1325);
PAINT ORANGE (-4650 1325);
DISPLAY INVISIBLE (-4650 1325);
FORCEPROP 1 LAST COMMENT_BODY TRUE
J 0
(-4625 1425);
DISPLAY 0.978723 (-4625 1425);
PAINT ORANGE (-4625 1425);
DISPLAY INVISIBLE (-4625 1425);
FORCEADD INTEL_CORP_BPAGE..1
(0 0);
FORCEPROP 1 LAST CDS_CON_LAST_MODIFIED Fri Jun 16 17:48:25 2017
J 0
(-1425 325);
DISPLAY 1.340426 (-1425 325);
PAINT GREEN (-1425 325);
DISPLAY INVISIBLE (-1425 325);
FORCEPROP 1 LAST CUSTOM_TXT_CDS <CURRENT_DESIGN_SHEET> OF <TOTAL_DESIGN_SHEETS>
J 0
(-500 25);
PAINT ORANGE (-500 25);
FORCEPROP 1 LAST CUSTOM_TXT_CDS <CON_LAST_MODIFIED>
J 0
(-4000 100);
PAINT ORANGE (-4000 100);
FORCEPROP 2 LAST CUSTOM_TXT_CDS <XR_PAGE_TITLE>
J 0
(-7890 5250);
DISPLAY 0.638298 (-7890 5250);
PAINT PINK (-7890 5250);
DISPLAY INVISIBLE (-7890 5250);
FORCEPROP 1 LAST SCH_TITLE SKYLAKE - SKT1 - 11 OF 21
J 0
(-7950 50);
DISPLAY 1.212766 (-7950 50);
PAINT GREEN (-7950 50);
FORCEPROP 2 LAST CDS_LIB mstr_symbols
J 0
(0 0);
PAINT ORANGE (0 0);
DISPLAY INVISIBLE (0 0);
FORCEPROP 2 LAST PAGE_BORDER TRUE
J 0
(-7890 5250);
DISPLAY 0.851064 (-7890 5250);
PAINT PINK (-7890 5250);
DISPLAY INVISIBLE (-7890 5250);
FORCEPROP 1 LAST COMMENT_BODY TRUE
J 0
(12 12);
DISPLAY 0.638298 (12 12);
PAINT GREEN (12 12);
DISPLAY INVISIBLE (12 12);
FORCEPROP 2 LAST CDS_XR_PAGE_TITLE CR-65 : @BASEBOARD_FAB2_LIB.BASEBOARD_FAB2(SCH_1):PAGE65
J 0
(-7890 5250);
DISPLAY 0.638298 (-7890 5250);
PAINT PINK (-7890 5250);
DISPLAY INVISIBLE (-7890 5250);
FORCEADD PRELIM..10
(-4140 2565);
PAINT GRAY (-4140 2565);
FORCEPROP 2 LAST CDS_LIB mstr_misc
J 0
(-4140 2565);
PAINT ORANGE (-4140 2565);
DISPLAY INVISIBLE (-4140 2565);
FORCEPROP 1 LAST COMMENT_BODY TRUE
J 0
(-4140 2565);
PAINT ORANGE (-4140 2565);
DISPLAY INVISIBLE (-4140 2565);
WIRE 17 -1 (-2750 1650)(-2750 1700);
WIRE 17 -1 (-2750 1700)(-2750 1750);
WIRE 17 -1 (-2750 1750)(-2750 1800);
WIRE 17 -1 (-2750 1800)(-2750 2150);
WIRE 17 -1 (-2750 2150)(-2750 2200);
WIRE 17 -1 (-2750 2200)(-2750 2250);
WIRE 17 -1 (-2750 2250)(-2750 2300);
WIRE 17 -1 (-2750 2300)(-2750 2650);
WIRE 17 -1 (-2750 2650)(-2750 2700);
WIRE 17 -1 (-2750 2700)(-2750 2750);
WIRE 17 -1 (-2750 2750)(-2750 2800);
WIRE 17 -1 (-2750 2800)(-2750 3150);
WIRE 17 -1 (-2750 3150)(-2750 3200);
WIRE 17 -1 (-2750 3200)(-2750 3250);
WIRE 17 -1 (-2750 3500)(-1575 3500);
FORCEPROP 2 LAST SIG_NAME TP_P3E_CPU1_PE2_RSR_TXN<15:0>
J 0
(-2710 3510);
DISPLAY 0.617021 (-2710 3510);
PAINT ORANGE (-2710 3510);
FORCEPROP 2 LASTPROP $XRERR UNIQUE?
J 0
(-1545 3500);
DISPLAY 0.638298 (-1545 3500);
PAINT MONO (-1545 3500);
DISPLAY INVISIBLE (-1545 3500);
WIRE 17 -1 (-2750 3250)(-2750 3300);
WIRE 17 -1 (-2750 3300)(-2750 3500);
WIRE 17 -1 (-2900 1900)(-2900 1950);
WIRE 17 -1 (-2900 1950)(-2900 2000);
WIRE 17 -1 (-2900 2000)(-2900 2050);
WIRE 17 -1 (-2900 2050)(-2900 2400);
WIRE 17 -1 (-2900 2400)(-2900 2450);
WIRE 17 -1 (-2900 2450)(-2900 2500);
WIRE 17 -1 (-2900 2500)(-2900 2550);
WIRE 17 -1 (-2900 2550)(-2900 2900);
WIRE 17 -1 (-2900 2900)(-2900 2950);
WIRE 17 -1 (-2900 2950)(-2900 3000);
WIRE 17 -1 (-2900 3000)(-2900 3050);
WIRE 17 -1 (-2900 3050)(-2900 3400);
WIRE 17 -1 (-2900 3450)(-2900 3400);
WIRE 17 -1 (-2900 3450)(-2900 3500);
WIRE 17 -1 (-2900 3625)(-1575 3625);
FORCEPROP 2 LAST SIG_NAME TP_P3E_CPU1_PE2_RSR_TXP<15:0>
J 0
(-2710 3635);
DISPLAY 0.617021 (-2710 3635);
PAINT ORANGE (-2710 3635);
FORCEPROP 2 LASTPROP $XRERR UNIQUE?
J 0
(-1545 3625);
DISPLAY 0.638298 (-1545 3625);
PAINT MONO (-1545 3625);
DISPLAY INVISIBLE (-1545 3625);
WIRE 17 -1 (-2900 3500)(-2900 3550);
WIRE 17 -1 (-2900 3550)(-2900 3625);
WIRE 17 -1 (-5625 1700)(-5625 1650);
WIRE 17 -1 (-5625 1750)(-5625 1700);
WIRE 17 -1 (-5625 1800)(-5625 1750);
WIRE 17 -1 (-5625 2150)(-5625 1800);
WIRE 17 -1 (-5625 2200)(-5625 2150);
WIRE 17 -1 (-5625 2200)(-5625 2250);
WIRE 17 -1 (-5625 2250)(-5625 2300);
WIRE 17 -1 (-5625 2300)(-5625 2650);
WIRE 17 -1 (-5625 2700)(-5625 2650);
WIRE 17 -1 (-5625 2750)(-5625 2700);
WIRE 17 -1 (-5625 2800)(-5625 2750);
WIRE 17 -1 (-5625 3150)(-5625 2800);
WIRE 17 -1 (-5625 3200)(-5625 3150);
WIRE 17 -1 (-5625 3250)(-5625 3200);
WIRE 17 -1 (-6775 3600)(-5625 3600);
FORCEPROP 2 LAST SIG_NAME TP_P3E_CPU1_PE2_RSR_RXN<15:0>
J 0
(-6760 3610);
DISPLAY 0.617021 (-6760 3610);
PAINT ORANGE (-6760 3610);
FORCEPROP 2 LASTPROP $XRERR UNIQUE?
J 0
(-7015 3600);
DISPLAY 0.638298 (-7015 3600);
PAINT MONO (-7015 3600);
DISPLAY INVISIBLE (-7015 3600);
WIRE 17 -1 (-5625 3250)(-5625 3300);
WIRE 17 -1 (-5625 3300)(-5625 3600);
WIRE 17 -1 (-5475 1950)(-5475 1900);
WIRE 17 -1 (-5475 2000)(-5475 1950);
WIRE 17 -1 (-5475 2000)(-5475 2050);
WIRE 17 -1 (-5475 2050)(-5475 2400);
WIRE 17 -1 (-5475 2450)(-5475 2400);
WIRE 17 -1 (-5475 2500)(-5475 2450);
WIRE 17 -1 (-5475 2550)(-5475 2500);
WIRE 17 -1 (-5475 2900)(-5475 2550);
WIRE 17 -1 (-5475 2950)(-5475 2900);
WIRE 17 -1 (-5475 3000)(-5475 2950);
WIRE 17 -1 (-5475 3050)(-5475 3000);
WIRE 17 -1 (-5475 3400)(-5475 3050);
WIRE 17 -1 (-5475 3450)(-5475 3400);
WIRE 17 -1 (-5475 3500)(-5475 3450);
WIRE 17 -1 (-5475 3550)(-5475 3500);
WIRE 17 -1 (-6775 3700)(-5475 3700);
FORCEPROP 2 LAST SIG_NAME TP_P3E_CPU1_PE2_RSR_RXP<15:0>
J 0
(-6760 3710);
DISPLAY 0.617021 (-6760 3710);
PAINT ORANGE (-6760 3710);
FORCEPROP 2 LASTPROP $XRERR UNIQUE?
J 0
(-7015 3700);
DISPLAY 0.638298 (-7015 3700);
PAINT MONO (-7015 3700);
DISPLAY INVISIBLE (-7015 3700);
WIRE 17 -1 (-5475 3700)(-5475 3550);
WIRE 16 -1 (-2850 3225)(-3400 3225);
WIRE 16 -1 (-5375 2925)(-4900 2925);
WIRE 16 -1 (-5375 3025)(-4900 3025);
WIRE 16 -1 (-5525 3225)(-4900 3225);
WIRE 16 -1 (-5375 2975)(-4900 2975);
WIRE 16 -1 (-5375 1875)(-4900 1875);
WIRE 16 -1 (-5375 1925)(-4900 1925);
WIRE 16 -1 (-5375 1975)(-4900 1975);
WIRE 16 -1 (-5375 2025)(-4900 2025);
WIRE 16 -1 (-4900 1625)(-5525 1625);
WIRE 16 -1 (-4900 1675)(-5525 1675);
WIRE 16 -1 (-4900 1725)(-5525 1725);
WIRE 16 -1 (-4900 1775)(-5525 1775);
WIRE 16 -1 (-4900 2375)(-5375 2375);
WIRE 16 -1 (-5375 2425)(-4900 2425);
WIRE 16 -1 (-5375 2475)(-4900 2475);
WIRE 16 -1 (-5375 2525)(-4900 2525);
WIRE 16 -1 (-5375 2875)(-4900 2875);
WIRE 16 -1 (-5375 3375)(-4900 3375);
WIRE 16 -1 (-5375 3425)(-4900 3425);
WIRE 16 -1 (-5375 3475)(-4900 3475);
WIRE 16 -1 (-5375 3525)(-4900 3525);
WIRE 16 -1 (-4900 2125)(-5525 2125);
WIRE 16 -1 (-5525 2175)(-4900 2175);
WIRE 16 -1 (-5525 2225)(-4900 2225);
WIRE 16 -1 (-5525 2275)(-4900 2275);
WIRE 16 -1 (-5525 2625)(-4900 2625);
WIRE 16 -1 (-5525 2675)(-4900 2675);
WIRE 16 -1 (-5525 2725)(-4900 2725);
WIRE 16 -1 (-5525 2775)(-4900 2775);
WIRE 16 -1 (-5525 3125)(-4900 3125);
WIRE 16 -1 (-5525 3175)(-4900 3175);
WIRE 16 -1 (-5525 3275)(-4900 3275);
WIRE 16 -1 (-3400 1875)(-3000 1875);
WIRE 16 -1 (-3000 1925)(-3400 1925);
WIRE 16 -1 (-3400 1975)(-3000 1975);
WIRE 16 -1 (-3000 2025)(-3400 2025);
WIRE 16 -1 (-2850 1625)(-3400 1625);
WIRE 16 -1 (-2850 1675)(-3400 1675);
WIRE 16 -1 (-2850 1725)(-3400 1725);
WIRE 16 -1 (-2850 1775)(-3400 1775);
WIRE 16 -1 (-3000 2375)(-3400 2375);
WIRE 16 -1 (-3000 2425)(-3400 2425);
WIRE 16 -1 (-3000 2475)(-3400 2475);
WIRE 16 -1 (-3000 2525)(-3400 2525);
WIRE 16 -1 (-3000 2875)(-3400 2875);
WIRE 16 -1 (-3000 2925)(-3400 2925);
WIRE 16 -1 (-3000 2975)(-3400 2975);
WIRE 16 -1 (-3000 3025)(-3400 3025);
WIRE 16 -1 (-3000 3375)(-3400 3375);
WIRE 16 -1 (-3400 3425)(-3000 3425);
WIRE 16 -1 (-3400 3475)(-3000 3475);
WIRE 16 -1 (-3000 3525)(-3400 3525);
WIRE 16 -1 (-2850 2125)(-3400 2125);
WIRE 16 -1 (-2850 2175)(-3400 2175);
WIRE 16 -1 (-3400 2225)(-2850 2225);
WIRE 16 -1 (-3400 2275)(-2850 2275);
WIRE 16 -1 (-2850 2625)(-3400 2625);
WIRE 16 -1 (-3400 2675)(-2850 2675);
WIRE 16 -1 (-2850 2725)(-3400 2725);
WIRE 16 -1 (-2850 2775)(-3400 2775);
WIRE 16 -1 (-3400 3125)(-2850 3125);
WIRE 16 -1 (-2850 3175)(-3400 3175);
WIRE 16 -1 (-2850 3275)(-3400 3275);
FORCENOTE
BOM_COST=PROC_SOCKET
(-7900 250) 0;
DISPLAY LEFT (-7900 250);
DISPLAY 1.723404 (-7900 250);
PAINT PURPLE (-7900 250);
FORCENOTE
ROOM=CPU1
(-7900 375) 0;
DISPLAY LEFT (-7900 375);
DISPLAY 1.723404 (-7900 375);
PAINT PURPLE (-7900 375);
QUIT
